FILE_TYPE = MACRO_DRAWING;
SET COLOR_WIRE YELLOW;
SET COLOR_PROP ORANGE;
SET COLOR_DOT WHITE;
SET COLOR_ARC YELLOW;
SET COLOR_BODY GREEN;
SET COLOR_NOTE PURPLE;
SET PROP_DISPLAY VALUE;
SET PAGE_NUMBER P167;
FORCEADD UNIVERSAL_GND..1
(-8450 2225);
FORCEPROP 3 LASTPIN (-8450 2275) SIG_NAME GND\g
J 0
(-8440 2285);
DISPLAY 0.659574 (-8440 2285);
PAINT MONO (-8440 2285);
DISPLAY INVISIBLE (-8440 2285);
FORCEPROP 2 LAST CDS_LIB pure_quanta_power
J 0
(-8450 2225);
DISPLAY INVISIBLE (-8450 2225);
FORCEPROP 1 LAST HDL_POWER GND
J 1
(-8425 2150);
DISPLAY 0.872340 (-8425 2150);
PAINT GREEN (-8425 2150);
DISPLAY INVISIBLE (-8425 2150);
FORCEPROP 1 LAST PATH I1
J 0
(-8375 2225);
DISPLAY 0.872340 (-8375 2225);
PAINT AQUA (-8375 2225);
DISPLAY INVISIBLE (-8375 2225);
FORCEADD Q_INDUCTOR..1
(-10050 4675);
FORCEPROP 1 LAST LOCATION PL71
J 0
(-10175 4835);
DISPLAY 0.489362 (-10175 4835);
PAINT SKYBLUE (-10175 4835);
FORCEPROP 0 LAST SEC 1
J 0
(-10175 4950);
DISPLAY 0.680851 (-10175 4950);
PAINT MONO (-10175 4950);
DISPLAY INVISIBLE (-10175 4950);
FORCEPROP 0 LASTPIN (-10150 4650) $PN 1
J 2
(-10160 4660);
DISPLAY 0.489362 (-10160 4660);
PAINT MONO (-10160 4660);
FORCEPROP 0 LASTPIN (-9950 4650) $PN 2
J 0
(-9960 4660);
DISPLAY 0.489362 (-9960 4660);
PAINT MONO (-9960 4660);
FORCEPROP 1 LAST MATERIAL IND
J 0
(-10175 4730);
DISPLAY 0.489362 (-10175 4730);
PAINT SKYBLUE (-10175 4730);
FORCEPROP 2 LAST VALUE BLM18SN220TN1D/8000MA
J 0
(-10175 4875);
DISPLAY 0.489362 (-10175 4875);
PAINT SKYBLUE (-10175 4875);
FORCEPROP 2 LAST PACK_TYPE SMLF
J 0
(-10175 4925);
DISPLAY 0.489362 (-10175 4925);
PAINT SKYBLUE (-10175 4925);
FORCEPROP 2 LAST CDS_LIB pure_quanta
J 0
(-10050 4675);
DISPLAY INVISIBLE (-10050 4675);
FORCEPROP 1 LAST NEEDS_NO_SIZE TRUE
J 0
(-10050 4675);
DISPLAY 0.468085 (-10050 4675);
PAINT GREEN (-10050 4675);
DISPLAY INVISIBLE (-10050 4675);
FORCEPROP 2 LAST SEC_TYPE SMLF
J 0
(-10175 4950);
DISPLAY 1.021277 (-10175 4950);
DISPLAY INVISIBLE (-10175 4950);
FORCEPROP 1 LAST PATH I10
J 0
(-9975 4730);
DISPLAY 0.723404 (-9975 4730);
PAINT GREEN (-9975 4730);
DISPLAY INVISIBLE (-9975 4730);
FORCEPROP 1 LAST PART_NUMBER CX220TN1001
J 0
(-10175 4785);
DISPLAY 0.489362 (-10175 4785);
PAINT SKYBLUE (-10175 4785);
DISPLAY INVISIBLE (-10175 4785);
FORCEADD UNIVERSAL_GND..1
(-9175 4100);
FORCEPROP 3 LASTPIN (-9175 4150) SIG_NAME GND\g
J 0
(-9165 4160);
DISPLAY 0.659574 (-9165 4160);
PAINT MONO (-9165 4160);
DISPLAY INVISIBLE (-9165 4160);
FORCEPROP 2 LAST CDS_LIB pure_quanta_power
J 0
(-9175 4100);
DISPLAY INVISIBLE (-9175 4100);
FORCEPROP 1 LAST HDL_POWER GND
J 1
(-9150 4025);
DISPLAY 0.872340 (-9150 4025);
PAINT GREEN (-9150 4025);
DISPLAY INVISIBLE (-9150 4025);
FORCEPROP 1 LAST PATH I11
J 0
(-9100 4100);
DISPLAY 0.872340 (-9100 4100);
PAINT AQUA (-9100 4100);
DISPLAY INVISIBLE (-9100 4100);
FORCEADD Q_CAP..1
(-9025 4500);
FORCEPROP 1 LAST LOCATION PC119
J 0
(-8975 4600);
DISPLAY 0.489362 (-8975 4600);
PAINT SKYBLUE (-8975 4600);
FORCEPROP 2 LAST SEC 1
J 0
(-8975 4700);
DISPLAY 0.680851 (-8975 4700);
PAINT MONO (-8975 4700);
DISPLAY INVISIBLE (-8975 4700);
FORCEPROP 1 LASTPIN (-9025 4600) $PN 1
J 0
(-9015 4580);
DISPLAY 0.489362 (-9015 4580);
PAINT MONO (-9015 4580);
FORCEPROP 1 LASTPIN (-9025 4400) $PN 2
J 0
(-9015 4380);
DISPLAY 0.489362 (-9015 4380);
PAINT MONO (-9015 4380);
FORCEPROP 1 LAST PACK_TYPE C0805
J 0
(-8975 4300);
DISPLAY 0.489362 (-8975 4300);
PAINT SKYBLUE (-8975 4300);
FORCEPROP 1 LAST VOLTAGE 16V
J 0
(-8975 4500);
DISPLAY 0.489362 (-8975 4500);
PAINT SKYBLUE (-8975 4500);
FORCEPROP 1 LAST TOLERANCE 20%
J 0
(-8975 4450);
DISPLAY 0.489362 (-8975 4450);
PAINT SKYBLUE (-8975 4450);
FORCEPROP 1 LAST MATERIAL X6S
J 0
(-8975 4400);
DISPLAY 0.489362 (-8975 4400);
PAINT SKYBLUE (-8975 4400);
FORCEPROP 1 LAST VALUE 22UF
J 0
(-8975 4550);
DISPLAY 0.489362 (-8975 4550);
PAINT SKYBLUE (-8975 4550);
FORCEPROP 2 LAST CDS_LIB pure_quanta
J 0
(-9025 4500);
DISPLAY INVISIBLE (-9025 4500);
FORCEPROP 2 LAST SEC_TYPE C0805
J 0
(-8975 4700);
DISPLAY 1.021277 (-8975 4700);
DISPLAY INVISIBLE (-8975 4700);
FORCEPROP 1 LAST PATH I12
J 0
(-8975 4650);
DISPLAY 0.978723 (-8975 4650);
PAINT WHITE (-8975 4650);
DISPLAY INVISIBLE (-8975 4650);
FORCEPROP 1 LAST PART_NUMBER CH6223MEA01
J 0
(-8975 4350);
DISPLAY 0.489362 (-8975 4350);
PAINT SKYBLUE (-8975 4350);
DISPLAY INVISIBLE (-8975 4350);
FORCEADD Q_CAP..1
(-8675 4475);
FORCEPROP 1 LAST LOCATION PC120
J 0
(-8625 4575);
DISPLAY 0.489362 (-8625 4575);
PAINT SKYBLUE (-8625 4575);
FORCEPROP 0 LAST SEC 1
J 0
(-8625 4600);
DISPLAY 0.680851 (-8625 4600);
PAINT MONO (-8625 4600);
DISPLAY INVISIBLE (-8625 4600);
FORCEPROP 1 LASTPIN (-8675 4575) $PN 1
J 0
(-8665 4555);
DISPLAY 0.489362 (-8665 4555);
PAINT MONO (-8665 4555);
FORCEPROP 1 LASTPIN (-8675 4375) $PN 2
J 0
(-8665 4355);
DISPLAY 0.489362 (-8665 4355);
PAINT MONO (-8665 4355);
FORCEPROP 1 LAST PACK_TYPE C0805
J 0
(-8625 4275);
DISPLAY 0.489362 (-8625 4275);
PAINT SKYBLUE (-8625 4275);
FORCEPROP 1 LAST VOLTAGE 16V
J 0
(-8625 4475);
DISPLAY 0.489362 (-8625 4475);
PAINT SKYBLUE (-8625 4475);
FORCEPROP 1 LAST VALUE 22UF
J 0
(-8625 4525);
DISPLAY 0.489362 (-8625 4525);
PAINT SKYBLUE (-8625 4525);
FORCEPROP 1 LAST TOLERANCE 20%
J 0
(-8625 4425);
DISPLAY 0.489362 (-8625 4425);
PAINT SKYBLUE (-8625 4425);
FORCEPROP 1 LAST MATERIAL X6S
J 0
(-8625 4375);
DISPLAY 0.489362 (-8625 4375);
PAINT SKYBLUE (-8625 4375);
FORCEPROP 2 LAST SEC_TYPE C0805
J 0
(-8625 4675);
DISPLAY 1.021277 (-8625 4675);
DISPLAY INVISIBLE (-8625 4675);
FORCEPROP 2 LAST CDS_LIB pure_quanta
J 0
(-8675 4475);
DISPLAY INVISIBLE (-8675 4475);
FORCEPROP 1 LAST PATH I13
J 0
(-8625 4625);
DISPLAY 0.978723 (-8625 4625);
PAINT WHITE (-8625 4625);
DISPLAY INVISIBLE (-8625 4625);
FORCEPROP 1 LAST PART_NUMBER CH6223MEA01
J 0
(-8625 4325);
DISPLAY 0.978723 (-8625 4325);
PAINT SKYBLUE (-8625 4325);
DISPLAY INVISIBLE (-8625 4325);
FORCEADD UNIVERSAL_GND..1
(-7875 2300);
FORCEPROP 3 LASTPIN (-7875 2350) SIG_NAME GND\g
J 0
(-7865 2360);
DISPLAY 0.659574 (-7865 2360);
PAINT MONO (-7865 2360);
DISPLAY INVISIBLE (-7865 2360);
FORCEPROP 2 LAST CDS_LIB pure_quanta_power
J 0
(-7875 2300);
DISPLAY INVISIBLE (-7875 2300);
FORCEPROP 1 LAST HDL_POWER GND
J 1
(-7850 2225);
DISPLAY 0.872340 (-7850 2225);
PAINT GREEN (-7850 2225);
DISPLAY INVISIBLE (-7850 2225);
FORCEPROP 1 LAST PATH I14
J 0
(-7800 2300);
DISPLAY 0.872340 (-7800 2300);
PAINT AQUA (-7800 2300);
DISPLAY INVISIBLE (-7800 2300);
FORCEADD Q_RES..2
(-7875 2575);
FORCEPROP 1 LAST LOCATION PR452
J 0
(-7830 2700);
DISPLAY 0.489362 (-7830 2700);
PAINT SKYBLUE (-7830 2700);
FORCEPROP 0 LAST SEC 1
J 0
(-7825 2725);
DISPLAY 0.680851 (-7825 2725);
PAINT MONO (-7825 2725);
DISPLAY INVISIBLE (-7825 2725);
FORCEPROP 1 LASTPIN (-7875 2675) $PN 1
J 0
(-7870 2637);
DISPLAY 0.489362 (-7870 2637);
PAINT MONO (-7870 2637);
FORCEPROP 1 LASTPIN (-7875 2475) $PN 2
J 0
(-7870 2485);
DISPLAY 0.489362 (-7870 2485);
PAINT MONO (-7870 2485);
FORCEPROP 1 LAST PACK_TYPE 0402LF
J 0
(-7835 2400);
DISPLAY 0.489362 (-7835 2400);
PAINT SKYBLUE (-7835 2400);
FORCEPROP 1 LAST WATTAGE 1/16W
J 0
(-7835 2550);
DISPLAY 0.489362 (-7835 2550);
PAINT SKYBLUE (-7835 2550);
FORCEPROP 1 LAST MATERIAL CHIP
J 0
(-7835 2500);
DISPLAY 0.489362 (-7835 2500);
PAINT SKYBLUE (-7835 2500);
FORCEPROP 1 LAST TOLERANCE 1%
J 0
(-7830 2600);
DISPLAY 0.489362 (-7830 2600);
PAINT SKYBLUE (-7830 2600);
FORCEPROP 1 LAST VALUE 6.98K
J 0
(-7830 2650);
DISPLAY 0.489362 (-7830 2650);
PAINT SKYBLUE (-7830 2650);
FORCEPROP 2 LAST SEC_TYPE 0402LF
J 0
(-7825 2800);
DISPLAY 1.021277 (-7825 2800);
DISPLAY INVISIBLE (-7825 2800);
FORCEPROP 2 LAST CDS_LIB pure_quanta
J 0
(-7875 2575);
DISPLAY INVISIBLE (-7875 2575);
FORCEPROP 1 LAST PATH I15
J 0
(-7825 2750);
DISPLAY 0.978723 (-7825 2750);
PAINT WHITE (-7825 2750);
DISPLAY INVISIBLE (-7825 2750);
FORCEPROP 1 LAST PART_NUMBER CS26982FB08
J 0
(-7835 2450);
DISPLAY 0.489362 (-7835 2450);
PAINT SKYBLUE (-7835 2450);
DISPLAY INVISIBLE (-7835 2450);
FORCEADD UNIVERSAL_GND..1
(-8225 3225);
FORCEPROP 3 LASTPIN (-8225 3275) SIG_NAME GND\g
J 0
(-8215 3285);
DISPLAY 0.659574 (-8215 3285);
PAINT MONO (-8215 3285);
DISPLAY INVISIBLE (-8215 3285);
FORCEPROP 2 LAST CDS_LIB pure_quanta_power
J 0
(-8225 3225);
DISPLAY INVISIBLE (-8225 3225);
FORCEPROP 1 LAST HDL_POWER GND
J 1
(-8200 3150);
DISPLAY 0.872340 (-8200 3150);
PAINT GREEN (-8200 3150);
DISPLAY INVISIBLE (-8200 3150);
FORCEPROP 1 LAST PATH I16
J 0
(-8150 3225);
DISPLAY 0.872340 (-8150 3225);
PAINT AQUA (-8150 3225);
DISPLAY INVISIBLE (-8150 3225);
FORCEADD Q_RES..1
(-7950 3400);
FORCEPROP 1 LAST LOCATION PR6000
J 0
(-8175 3425);
DISPLAY 0.638298 (-8175 3425);
FORCEPROP 0 LAST $SEC 1
J 0
(-7825 3475);
DISPLAY 0.680851 (-7825 3475);
PAINT MONO (-7825 3475);
DISPLAY INVISIBLE (-7825 3475);
FORCEPROP 0 LAST CDS_SEC 1
J 0
(-7825 3475);
DISPLAY 0.680851 (-7825 3475);
DISPLAY INVISIBLE (-7825 3475);
FORCEPROP 1 LASTPIN (-8050 3400) $PN 1
J 0
(-8038 3412);
DISPLAY 0.787234 (-8038 3412);
PAINT MONO (-8038 3412);
FORCEPROP 1 LASTPIN (-7850 3400) $PN 2
J 0
(-7888 3412);
DISPLAY 0.787234 (-7888 3412);
PAINT MONO (-7888 3412);
FORCEPROP 1 LAST PACK_TYPE 0402LF
J 0
(-8150 3300);
DISPLAY 0.638298 (-8150 3300);
FORCEPROP 1 LAST TOLERANCE 5%
J 0
(-7825 3425);
DISPLAY 0.638298 (-7825 3425);
FORCEPROP 1 LAST MATERIAL CHIP
J 0
(-8150 3350);
DISPLAY 0.638298 (-8150 3350);
FORCEPROP 1 LAST WATTAGE 1/16W
J 2
(-7775 3350);
DISPLAY 0.638298 (-7775 3350);
FORCEPROP 1 LAST VALUE 0
J 2
(-7925 3425);
DISPLAY 0.638298 (-7925 3425);
FORCEPROP 2 LAST CDS_LIB pure_quanta
J 0
(-7950 3400);
DISPLAY INVISIBLE (-7950 3400);
FORCEPROP 1 LAST PATH I17
J 0
(-8000 3550);
DISPLAY 0.978723 (-8000 3550);
PAINT WHITE (-8000 3550);
DISPLAY INVISIBLE (-8000 3550);
FORCEPROP 1 LAST PART_NUMBER CS00002JB13
J 0
(-7925 3300);
DISPLAY 0.638298 (-7925 3300);
DISPLAY INVISIBLE (-7925 3300);
FORCEADD UNIVERSAL_GND..1
(-6375 2550);
FORCEPROP 3 LASTPIN (-6375 2600) SIG_NAME GND\g
J 0
(-6365 2610);
DISPLAY 0.659574 (-6365 2610);
PAINT MONO (-6365 2610);
DISPLAY INVISIBLE (-6365 2610);
FORCEPROP 2 LAST CDS_LIB pure_quanta_power
J 0
(-6375 2550);
DISPLAY INVISIBLE (-6375 2550);
FORCEPROP 1 LAST HDL_POWER GND
J 1
(-6350 2475);
DISPLAY 0.872340 (-6350 2475);
PAINT GREEN (-6350 2475);
DISPLAY INVISIBLE (-6350 2475);
FORCEPROP 1 LAST PATH I18
J 0
(-6300 2550);
DISPLAY 0.872340 (-6300 2550);
PAINT AQUA (-6300 2550);
DISPLAY INVISIBLE (-6300 2550);
FORCEADD Q_CAP..1
(-6125 2750);
FORCEPROP 1 LAST LOCATION PC127
J 0
(-6075 2850);
DISPLAY 0.489362 (-6075 2850);
PAINT SKYBLUE (-6075 2850);
FORCEPROP 0 LAST SEC 1
J 0
(-6075 2875);
DISPLAY 0.680851 (-6075 2875);
PAINT MONO (-6075 2875);
DISPLAY INVISIBLE (-6075 2875);
FORCEPROP 1 LASTPIN (-6125 2850) $PN 1
J 0
(-6115 2830);
DISPLAY 0.489362 (-6115 2830);
PAINT MONO (-6115 2830);
FORCEPROP 1 LASTPIN (-6125 2650) $PN 2
J 0
(-6115 2630);
DISPLAY 0.489362 (-6115 2630);
PAINT MONO (-6115 2630);
FORCEPROP 1 LAST VOLTAGE 25V
J 0
(-6075 2750);
DISPLAY 0.489362 (-6075 2750);
PAINT SKYBLUE (-6075 2750);
FORCEPROP 1 LAST PACK_TYPE 0402
J 0
(-6075 2550);
DISPLAY 0.489362 (-6075 2550);
PAINT SKYBLUE (-6075 2550);
FORCEPROP 1 LAST VALUE 0.1UF
J 0
(-6075 2800);
DISPLAY 0.489362 (-6075 2800);
PAINT SKYBLUE (-6075 2800);
FORCEPROP 1 LAST TOLERANCE 10%
J 0
(-6075 2700);
DISPLAY 0.489362 (-6075 2700);
PAINT SKYBLUE (-6075 2700);
FORCEPROP 1 LAST MATERIAL X7R
J 0
(-6075 2650);
DISPLAY 0.489362 (-6075 2650);
PAINT SKYBLUE (-6075 2650);
FORCEPROP 2 LAST SEC_TYPE 0402
J 0
(-6075 2950);
DISPLAY 1.021277 (-6075 2950);
DISPLAY INVISIBLE (-6075 2950);
FORCEPROP 2 LAST CDS_LIB pure_quanta
J 0
(-6125 2750);
DISPLAY INVISIBLE (-6125 2750);
FORCEPROP 1 LAST PATH I19
J 0
(-6075 2900);
DISPLAY 0.978723 (-6075 2900);
PAINT WHITE (-6075 2900);
DISPLAY INVISIBLE (-6075 2900);
FORCEPROP 1 LAST PART_NUMBER CH4104K1B00
J 0
(-6075 2600);
DISPLAY 0.489362 (-6075 2600);
PAINT SKYBLUE (-6075 2600);
DISPLAY INVISIBLE (-6075 2600);
FORCEADD Q_CAP..1
R 2
(-8450 2500);
FORCEPROP 1 LAST LOCATION PC118
J 0
(-8400 2640);
DISPLAY 0.489362 (-8400 2640);
PAINT SKYBLUE (-8400 2640);
FORCEPROP 0 LAST SEC 1
J 0
(-8400 2665);
DISPLAY 0.680851 (-8400 2665);
PAINT MONO (-8400 2665);
DISPLAY INVISIBLE (-8400 2665);
FORCEPROP 1 LASTPIN (-8450 2600) $PN 1
J 2
(-8410 2575);
DISPLAY 0.489362 (-8410 2575);
PAINT MONO (-8410 2575);
FORCEPROP 1 LASTPIN (-8450 2400) $PN 2
J 2
(-8410 2385);
DISPLAY 0.489362 (-8410 2385);
PAINT MONO (-8410 2385);
FORCEPROP 1 LAST VALUE 1UF
J 0
(-8400 2578);
DISPLAY 0.489362 (-8400 2578);
PAINT SKYBLUE (-8400 2578);
FORCEPROP 1 LAST MATERIAL X6S
J 0
(-8400 2431);
DISPLAY 0.489362 (-8400 2431);
PAINT SKYBLUE (-8400 2431);
FORCEPROP 1 LAST TOLERANCE 10%
J 0
(-8400 2480);
DISPLAY 0.489362 (-8400 2480);
PAINT SKYBLUE (-8400 2480);
FORCEPROP 1 LAST VOLTAGE 25V
J 0
(-8400 2529);
DISPLAY 0.489362 (-8400 2529);
PAINT SKYBLUE (-8400 2529);
FORCEPROP 1 LAST PACK_TYPE C0402
J 0
(-8400 2382);
DISPLAY 0.489362 (-8400 2382);
PAINT SKYBLUE (-8400 2382);
FORCEPROP 2 LAST SIGNAL_MODEL DEFAULT_CAPACITOR_100000PF_2_1
R 3
J 1
(-8520 2448);
DISPLAY 0.744681 (-8520 2448);
PAINT MONO (-8520 2448);
DISPLAY INVISIBLE (-8520 2448);
FORCEPROP 2 LAST CDS_LIB pure_quanta
J 0
(-8450 2500);
DISPLAY INVISIBLE (-8450 2500);
FORCEPROP 2 LAST SEC_TYPE C0402
J 0
(-8500 2715);
DISPLAY 1.021277 (-8500 2715);
DISPLAY INVISIBLE (-8500 2715);
FORCEPROP 1 LAST PATH I2
J 2
(-8500 2650);
DISPLAY 0.978723 (-8500 2650);
PAINT WHITE (-8500 2650);
DISPLAY INVISIBLE (-8500 2650);
FORCEPROP 1 LAST PART_NUMBER CH5104KEB02
J 0
(-8400 2333);
DISPLAY 0.489362 (-8400 2333);
PAINT SKYBLUE (-8400 2333);
DISPLAY INVISIBLE (-8400 2333);
FORCEADD UNIVERSAL_GND..1
(-6125 2550);
FORCEPROP 3 LASTPIN (-6125 2600) SIG_NAME GND\g
J 0
(-6115 2610);
DISPLAY 0.659574 (-6115 2610);
PAINT MONO (-6115 2610);
DISPLAY INVISIBLE (-6115 2610);
FORCEPROP 2 LAST CDS_LIB pure_quanta_power
J 0
(-6125 2550);
DISPLAY INVISIBLE (-6125 2550);
FORCEPROP 1 LAST HDL_POWER GND
J 1
(-6100 2475);
DISPLAY 0.872340 (-6100 2475);
PAINT GREEN (-6100 2475);
DISPLAY INVISIBLE (-6100 2475);
FORCEPROP 1 LAST PATH I20
J 0
(-6050 2550);
DISPLAY 0.872340 (-6050 2550);
PAINT AQUA (-6050 2550);
DISPLAY INVISIBLE (-6050 2550);
FORCEADD UNIVERSAL_GND..1
(-5775 2550);
FORCEPROP 3 LASTPIN (-5775 2600) SIG_NAME GND\g
J 0
(-5765 2610);
DISPLAY 0.659574 (-5765 2610);
PAINT MONO (-5765 2610);
DISPLAY INVISIBLE (-5765 2610);
FORCEPROP 2 LAST CDS_LIB pure_quanta_power
J 0
(-5775 2550);
DISPLAY INVISIBLE (-5775 2550);
FORCEPROP 1 LAST HDL_POWER GND
J 1
(-5750 2475);
DISPLAY 0.872340 (-5750 2475);
PAINT GREEN (-5750 2475);
DISPLAY INVISIBLE (-5750 2475);
FORCEPROP 1 LAST PATH I21
J 0
(-5700 2550);
DISPLAY 0.872340 (-5700 2550);
PAINT AQUA (-5700 2550);
DISPLAY INVISIBLE (-5700 2550);
FORCEADD UNIVERSAL_GND..1
(-5175 2125);
FORCEPROP 3 LASTPIN (-5175 2175) SIG_NAME GND\g
J 0
(-5165 2185);
DISPLAY 0.659574 (-5165 2185);
PAINT MONO (-5165 2185);
DISPLAY INVISIBLE (-5165 2185);
FORCEPROP 2 LAST CDS_LIB pure_quanta_power
J 0
(-5175 2125);
DISPLAY INVISIBLE (-5175 2125);
FORCEPROP 1 LAST HDL_POWER GND
J 1
(-5150 2050);
DISPLAY 0.872340 (-5150 2050);
PAINT GREEN (-5150 2050);
DISPLAY INVISIBLE (-5150 2050);
FORCEPROP 1 LAST PATH I22
J 0
(-5100 2125);
DISPLAY 0.872340 (-5100 2125);
PAINT AQUA (-5100 2125);
DISPLAY INVISIBLE (-5100 2125);
FORCEADD Q_RES..2
R 2
(-5175 2400);
FORCEPROP 1 LAST LOCATION PR454
J 0
(-5125 2500);
DISPLAY 0.489362 (-5125 2500);
PAINT SKYBLUE (-5125 2500);
FORCEPROP 0 LAST SEC 1
J 0
(-5125 2525);
DISPLAY 0.680851 (-5125 2525);
PAINT MONO (-5125 2525);
DISPLAY INVISIBLE (-5125 2525);
FORCEPROP 1 LASTPIN (-5175 2500) $PN 1
J 2
(-5180 2462);
DISPLAY 0.489362 (-5180 2462);
PAINT MONO (-5180 2462);
FORCEPROP 1 LASTPIN (-5175 2300) $PN 2
J 2
(-5180 2310);
DISPLAY 0.489362 (-5180 2310);
PAINT MONO (-5180 2310);
FORCEPROP 1 LAST PACK_TYPE 0402LF
J 0
(-5125 2200);
DISPLAY 0.489362 (-5125 2200);
PAINT SKYBLUE (-5125 2200);
FORCEPROP 1 LAST MATERIAL CHIP
J 0
(-5125 2300);
DISPLAY 0.489362 (-5125 2300);
PAINT SKYBLUE (-5125 2300);
FORCEPROP 1 LAST WATTAGE 1/16W
J 0
(-5125 2350);
DISPLAY 0.489362 (-5125 2350);
PAINT SKYBLUE (-5125 2350);
FORCEPROP 1 LAST TOLERANCE 1%
J 2
(-5075 2400);
DISPLAY 0.489362 (-5075 2400);
PAINT SKYBLUE (-5075 2400);
FORCEPROP 1 LAST VALUE 12.4K
J 0
(-5125 2450);
DISPLAY 0.489362 (-5125 2450);
PAINT SKYBLUE (-5125 2450);
FORCEPROP 2 LAST CDS_LIB pure_quanta
J 0
(-5175 2400);
DISPLAY INVISIBLE (-5175 2400);
FORCEPROP 2 LAST SEC_TYPE 0402LF
J 0
(-5225 2625);
DISPLAY 1.021277 (-5225 2625);
DISPLAY INVISIBLE (-5225 2625);
FORCEPROP 1 LAST PATH I23
J 2
(-5225 2575);
DISPLAY 0.978723 (-5225 2575);
PAINT WHITE (-5225 2575);
DISPLAY INVISIBLE (-5225 2575);
FORCEPROP 1 LAST PART_NUMBER CS31242FB02
J 0
(-5125 2250);
DISPLAY 0.489362 (-5125 2250);
PAINT SKYBLUE (-5125 2250);
DISPLAY INVISIBLE (-5125 2250);
FORCEADD Q_CAP..1
R 1
(-4225 2250);
FORCEPROP 1 LAST LOCATION PC132
J 0
(-4275 2300);
DISPLAY 0.489362 (-4275 2300);
PAINT SKYBLUE (-4275 2300);
FORCEPROP 0 LAST SEC 1
R 1
J 0
(-4275 2325);
DISPLAY 0.680851 (-4275 2325);
PAINT MONO (-4275 2325);
DISPLAY INVISIBLE (-4275 2325);
FORCEPROP 1 LASTPIN (-4325 2250) $PN 1
J 0
(-4305 2260);
DISPLAY 0.489362 (-4305 2260);
PAINT MONO (-4305 2260);
FORCEPROP 1 LASTPIN (-4125 2250) $PN 2
J 0
(-4160 2260);
DISPLAY 0.489362 (-4160 2260);
PAINT MONO (-4160 2260);
FORCEPROP 1 LAST PACK_TYPE 0402
J 0
(-4150 2150);
DISPLAY 0.489362 (-4150 2150);
PAINT SKYBLUE (-4150 2150);
FORCEPROP 1 LAST VOLTAGE 50V
J 0
(-4100 2275);
DISPLAY 0.489362 (-4100 2275);
PAINT SKYBLUE (-4100 2275);
FORCEPROP 1 LAST VALUE 100PF
J 0
(-4500 2275);
DISPLAY 0.489362 (-4500 2275);
PAINT SKYBLUE (-4500 2275);
FORCEPROP 1 LAST TOLERANCE 5%
J 0
(-4350 2275);
DISPLAY 0.489362 (-4350 2275);
PAINT SKYBLUE (-4350 2275);
FORCEPROP 1 LAST MATERIAL NPO
J 0
(-4125 2200);
DISPLAY 0.489362 (-4125 2200);
PAINT SKYBLUE (-4125 2200);
FORCEPROP 2 LAST SEC_TYPE 0402
J 0
(-4275 2325);
DISPLAY 1.021277 (-4275 2325);
DISPLAY INVISIBLE (-4275 2325);
FORCEPROP 2 LAST CDS_LIB pure_quanta
J 0
(-4225 2250);
DISPLAY INVISIBLE (-4225 2250);
FORCEPROP 1 LAST PATH I24
R 1
J 0
(-4375 2300);
DISPLAY 0.978723 (-4375 2300);
PAINT WHITE (-4375 2300);
DISPLAY INVISIBLE (-4375 2300);
FORCEPROP 1 LAST PART_NUMBER CH11006JB00
J 0
(-4550 2200);
DISPLAY 0.489362 (-4550 2200);
PAINT SKYBLUE (-4550 2200);
DISPLAY INVISIBLE (-4550 2200);
FORCEADD Q_RES..1
(-4225 2650);
FORCEPROP 1 LAST LOCATION PR455
J 0
(-4250 2700);
DISPLAY 0.489362 (-4250 2700);
PAINT SKYBLUE (-4250 2700);
FORCEPROP 0 LAST SEC 1
J 0
(-4250 2725);
DISPLAY 0.680851 (-4250 2725);
PAINT MONO (-4250 2725);
DISPLAY INVISIBLE (-4250 2725);
FORCEPROP 1 LASTPIN (-4325 2650) $PN 1
J 0
(-4313 2662);
DISPLAY 0.489362 (-4313 2662);
PAINT MONO (-4313 2662);
FORCEPROP 1 LASTPIN (-4125 2650) $PN 2
J 0
(-4163 2662);
DISPLAY 0.489362 (-4163 2662);
PAINT MONO (-4163 2662);
FORCEPROP 1 LAST PACK_TYPE 0402LF
J 0
(-4150 2550);
DISPLAY 0.489362 (-4150 2550);
PAINT SKYBLUE (-4150 2550);
FORCEPROP 1 LAST MATERIAL CHIP
J 0
(-4125 2600);
DISPLAY 0.489362 (-4125 2600);
PAINT SKYBLUE (-4125 2600);
FORCEPROP 1 LAST WATTAGE 1/16W
J 2
(-4025 2675);
DISPLAY 0.489362 (-4025 2675);
PAINT SKYBLUE (-4025 2675);
FORCEPROP 1 LAST TOLERANCE 1%
J 0
(-4375 2675);
DISPLAY 0.489362 (-4375 2675);
PAINT SKYBLUE (-4375 2675);
FORCEPROP 1 LAST VALUE 56K
J 2
(-4400 2675);
DISPLAY 0.489362 (-4400 2675);
PAINT SKYBLUE (-4400 2675);
FORCEPROP 2 LAST CDS_LIB pure_quanta
J 0
(-4225 2650);
DISPLAY INVISIBLE (-4225 2650);
FORCEPROP 2 LAST SEC_TYPE 0402LF
J 0
(-4275 2850);
DISPLAY 1.021277 (-4275 2850);
DISPLAY INVISIBLE (-4275 2850);
FORCEPROP 1 LAST PATH I25
J 0
(-4275 2800);
DISPLAY 0.978723 (-4275 2800);
PAINT WHITE (-4275 2800);
DISPLAY INVISIBLE (-4275 2800);
FORCEPROP 1 LAST PART_NUMBER CS35602FB00
J 0
(-4600 2600);
DISPLAY 0.489362 (-4600 2600);
PAINT SKYBLUE (-4600 2600);
DISPLAY INVISIBLE (-4600 2600);
FORCEADD Q_CAP..1
(-4575 3300);
FORCEPROP 1 LAST LOCATION PC129
J 0
(-4525 3400);
DISPLAY 0.489362 (-4525 3400);
PAINT SKYBLUE (-4525 3400);
FORCEPROP 2 LAST SEC 1
J 0
(-4525 3500);
DISPLAY 0.680851 (-4525 3500);
PAINT MONO (-4525 3500);
DISPLAY INVISIBLE (-4525 3500);
FORCEPROP 1 LASTPIN (-4575 3400) $PN 1
J 0
(-4565 3380);
DISPLAY 0.489362 (-4565 3380);
PAINT MONO (-4565 3380);
FORCEPROP 1 LASTPIN (-4575 3200) $PN 2
J 0
(-4565 3180);
DISPLAY 0.489362 (-4565 3180);
PAINT MONO (-4565 3180);
FORCEPROP 1 LAST VALUE 22UF
J 0
(-4525 3350);
DISPLAY 0.489362 (-4525 3350);
PAINT SKYBLUE (-4525 3350);
FORCEPROP 1 LAST MATERIAL X6S
J 0
(-4525 3200);
DISPLAY 0.489362 (-4525 3200);
PAINT SKYBLUE (-4525 3200);
FORCEPROP 1 LAST PACK_TYPE C0805
J 0
(-4525 3150);
DISPLAY 0.489362 (-4525 3150);
PAINT SKYBLUE (-4525 3150);
FORCEPROP 1 LAST VOLTAGE 16V
J 0
(-4525 3300);
DISPLAY 0.489362 (-4525 3300);
PAINT SKYBLUE (-4525 3300);
FORCEPROP 1 LAST TOLERANCE 20%
J 0
(-4525 3250);
DISPLAY 0.489362 (-4525 3250);
PAINT SKYBLUE (-4525 3250);
FORCEPROP 2 LAST SEC_TYPE C0805
J 0
(-4525 3500);
DISPLAY 1.021277 (-4525 3500);
DISPLAY INVISIBLE (-4525 3500);
FORCEPROP 2 LAST CDS_LIB pure_quanta
J 0
(-4575 3300);
DISPLAY INVISIBLE (-4575 3300);
FORCEPROP 1 LAST PATH I27
J 0
(-4525 3450);
DISPLAY 0.978723 (-4525 3450);
PAINT WHITE (-4525 3450);
DISPLAY INVISIBLE (-4525 3450);
FORCEPROP 1 LAST PART_NUMBER CH6223MEA01
J 0
(-4525 3150);
DISPLAY 0.978723 (-4525 3150);
PAINT SKYBLUE (-4525 3150);
DISPLAY INVISIBLE (-4525 3150);
FORCEADD Q_CAP..1
(-4275 3300);
FORCEPROP 1 LAST LOCATION PC130
J 0
(-4225 3400);
DISPLAY 0.489362 (-4225 3400);
PAINT SKYBLUE (-4225 3400);
FORCEPROP 2 LAST SEC 1
J 0
(-4225 3500);
DISPLAY 0.680851 (-4225 3500);
PAINT MONO (-4225 3500);
DISPLAY INVISIBLE (-4225 3500);
FORCEPROP 1 LASTPIN (-4275 3400) $PN 1
J 0
(-4265 3380);
DISPLAY 0.489362 (-4265 3380);
PAINT MONO (-4265 3380);
FORCEPROP 1 LASTPIN (-4275 3200) $PN 2
J 0
(-4265 3180);
DISPLAY 0.489362 (-4265 3180);
PAINT MONO (-4265 3180);
FORCEPROP 1 LAST MATERIAL X6S
J 0
(-4225 3200);
DISPLAY 0.489362 (-4225 3200);
PAINT SKYBLUE (-4225 3200);
FORCEPROP 1 LAST PACK_TYPE C0805
J 0
(-4225 3150);
DISPLAY 0.489362 (-4225 3150);
PAINT SKYBLUE (-4225 3150);
FORCEPROP 1 LAST TOLERANCE 20%
J 0
(-4225 3250);
DISPLAY 0.489362 (-4225 3250);
PAINT SKYBLUE (-4225 3250);
FORCEPROP 1 LAST VALUE 22UF
J 0
(-4225 3350);
DISPLAY 0.489362 (-4225 3350);
PAINT SKYBLUE (-4225 3350);
FORCEPROP 1 LAST VOLTAGE 16V
J 0
(-4225 3300);
DISPLAY 0.489362 (-4225 3300);
PAINT SKYBLUE (-4225 3300);
FORCEPROP 2 LAST SEC_TYPE C0805
J 0
(-4225 3500);
DISPLAY 1.021277 (-4225 3500);
DISPLAY INVISIBLE (-4225 3500);
FORCEPROP 2 LAST CDS_LIB pure_quanta
J 0
(-4275 3300);
DISPLAY INVISIBLE (-4275 3300);
FORCEPROP 1 LAST PATH I28
J 0
(-4225 3450);
DISPLAY 0.978723 (-4225 3450);
PAINT WHITE (-4225 3450);
DISPLAY INVISIBLE (-4225 3450);
FORCEPROP 1 LAST PART_NUMBER CH6223MEA01
J 0
(-4225 3150);
DISPLAY 0.978723 (-4225 3150);
PAINT SKYBLUE (-4225 3150);
DISPLAY INVISIBLE (-4225 3150);
FORCEADD Q_CAP..1
(-8275 4475);
FORCEPROP 1 LAST LOCATION PC123
J 0
(-8225 4575);
DISPLAY 0.489362 (-8225 4575);
PAINT SKYBLUE (-8225 4575);
FORCEPROP 0 LAST SEC 1
J 0
(-8225 4600);
DISPLAY 0.680851 (-8225 4600);
PAINT MONO (-8225 4600);
DISPLAY INVISIBLE (-8225 4600);
FORCEPROP 1 LASTPIN (-8275 4575) $PN 1
J 0
(-8265 4555);
DISPLAY 0.489362 (-8265 4555);
PAINT MONO (-8265 4555);
FORCEPROP 1 LASTPIN (-8275 4375) $PN 2
J 0
(-8265 4355);
DISPLAY 0.489362 (-8265 4355);
PAINT MONO (-8265 4355);
FORCEPROP 1 LAST TOLERANCE 20%
J 0
(-8225 4425);
DISPLAY 0.489362 (-8225 4425);
PAINT SKYBLUE (-8225 4425);
FORCEPROP 1 LAST VOLTAGE 16V
J 0
(-8225 4475);
DISPLAY 0.489362 (-8225 4475);
PAINT SKYBLUE (-8225 4475);
FORCEPROP 1 LAST VALUE 22UF
J 0
(-8225 4525);
DISPLAY 0.489362 (-8225 4525);
PAINT SKYBLUE (-8225 4525);
FORCEPROP 1 LAST PACK_TYPE C0805
J 0
(-8225 4275);
DISPLAY 0.489362 (-8225 4275);
PAINT SKYBLUE (-8225 4275);
FORCEPROP 1 LAST MATERIAL X6S
J 0
(-8225 4375);
DISPLAY 0.489362 (-8225 4375);
PAINT SKYBLUE (-8225 4375);
FORCEPROP 2 LAST SEC_TYPE C0805
J 0
(-8225 4675);
DISPLAY 1.021277 (-8225 4675);
DISPLAY INVISIBLE (-8225 4675);
FORCEPROP 2 LAST CDS_LIB pure_quanta
J 0
(-8275 4475);
DISPLAY INVISIBLE (-8275 4475);
FORCEPROP 1 LAST PATH I29
J 0
(-8225 4625);
DISPLAY 0.978723 (-8225 4625);
PAINT WHITE (-8225 4625);
DISPLAY INVISIBLE (-8225 4625);
FORCEPROP 1 LAST PART_NUMBER CH6223MEA01
J 0
(-8225 4325);
DISPLAY 0.978723 (-8225 4325);
PAINT SKYBLUE (-8225 4325);
DISPLAY INVISIBLE (-8225 4325);
FORCEADD OFFPAGE..1
(-8775 3600);
FORCEPROP 2 LAST $XR0 81 
J 0
(-8996 3600);
DISPLAY 0.638298 (-8996 3600);
PAINT MONO (-8996 3600);
FORCEPROP 2 LAST CDS_LIB standard
J 0
(-8775 3600);
DISPLAY INVISIBLE (-8775 3600);
FORCEPROP 1 LAST OFFPAGE TRUE
J 0
(-8450 3475);
DISPLAY 0.872340 (-8450 3475);
PAINT GREEN (-8450 3475);
DISPLAY INVISIBLE (-8450 3475);
FORCEPROP 1 LAST COMMENT_BODY TRUE
J 0
(-8650 3500);
DISPLAY 0.872340 (-8650 3500);
PAINT GREEN (-8650 3500);
DISPLAY INVISIBLE (-8650 3500);
FORCEPROP 2 LAST PATH I3
J 0
(-9025 3650);
DISPLAY 0.680851 (-9025 3650);
DISPLAY INVISIBLE (-9025 3650);
FORCEADD Q_CAP..1
(-7850 4475);
FORCEPROP 1 LAST LOCATION PC126
J 0
(-7800 4575);
DISPLAY 0.489362 (-7800 4575);
PAINT SKYBLUE (-7800 4575);
FORCEPROP 0 LAST $SEC 1
J 0
(-7800 4600);
DISPLAY 0.680851 (-7800 4600);
PAINT MONO (-7800 4600);
DISPLAY INVISIBLE (-7800 4600);
FORCEPROP 0 LAST CDS_SEC 1
J 0
(-7800 4600);
DISPLAY 0.680851 (-7800 4600);
DISPLAY INVISIBLE (-7800 4600);
FORCEPROP 1 LASTPIN (-7850 4575) $PN 1
J 0
(-7840 4555);
DISPLAY 0.787234 (-7840 4555);
PAINT MONO (-7840 4555);
FORCEPROP 1 LASTPIN (-7850 4375) $PN 2
J 0
(-7840 4355);
DISPLAY 0.787234 (-7840 4355);
PAINT MONO (-7840 4355);
FORCEPROP 1 LAST TOLERANCE 10%
J 0
(-7800 4425);
DISPLAY 0.489362 (-7800 4425);
PAINT SKYBLUE (-7800 4425);
FORCEPROP 1 LAST MATERIAL X6S
J 0
(-7800 4375);
DISPLAY 0.489362 (-7800 4375);
PAINT SKYBLUE (-7800 4375);
FORCEPROP 1 LAST PACK_TYPE C0402
J 0
(-7800 4275);
DISPLAY 0.489362 (-7800 4275);
PAINT SKYBLUE (-7800 4275);
FORCEPROP 1 LAST VOLTAGE 25V
J 0
(-7800 4475);
DISPLAY 0.489362 (-7800 4475);
PAINT SKYBLUE (-7800 4475);
FORCEPROP 1 LAST VALUE 1UF
J 0
(-7800 4525);
DISPLAY 0.489362 (-7800 4525);
PAINT SKYBLUE (-7800 4525);
FORCEPROP 2 LAST CDS_LIB pure_quanta
J 0
(-7850 4475);
DISPLAY INVISIBLE (-7850 4475);
FORCEPROP 1 LAST PATH I30
J 0
(-7800 4625);
DISPLAY 0.978723 (-7800 4625);
PAINT WHITE (-7800 4625);
DISPLAY INVISIBLE (-7800 4625);
FORCEPROP 1 LAST PART_NUMBER CH5104KEB02
J 0
(-7800 4325);
DISPLAY 0.489362 (-7800 4325);
PAINT SKYBLUE (-7800 4325);
DISPLAY INVISIBLE (-7800 4325);
FORCEADD Q_RES..2
(-6375 4450);
FORCEPROP 1 LAST LOCATION R453
J 0
(-6325 4575);
DISPLAY 0.489362 (-6325 4575);
PAINT SKYBLUE (-6325 4575);
FORCEPROP 0 LAST SEC 1
J 0
(-6325 4600);
DISPLAY 0.680851 (-6325 4600);
PAINT MONO (-6325 4600);
DISPLAY INVISIBLE (-6325 4600);
FORCEPROP 1 LASTPIN (-6375 4550) $PN 1
J 0
(-6370 4512);
DISPLAY 0.489362 (-6370 4512);
PAINT MONO (-6370 4512);
FORCEPROP 1 LASTPIN (-6375 4350) $PN 2
J 0
(-6370 4360);
DISPLAY 0.489362 (-6370 4360);
PAINT MONO (-6370 4360);
FORCEPROP 1 LAST PACK_TYPE 0402LF
J 0
(-6325 4300);
DISPLAY 0.489362 (-6325 4300);
PAINT SKYBLUE (-6325 4300);
FORCEPROP 1 LAST WATTAGE 1/16W
J 0
(-6325 4425);
DISPLAY 0.489362 (-6325 4425);
PAINT SKYBLUE (-6325 4425);
FORCEPROP 1 LAST TOLERANCE 5%
J 0
(-6325 4475);
DISPLAY 0.489362 (-6325 4475);
PAINT SKYBLUE (-6325 4475);
FORCEPROP 1 LAST VALUE 10K
J 0
(-6325 4525);
DISPLAY 0.489362 (-6325 4525);
PAINT SKYBLUE (-6325 4525);
FORCEPROP 2 LAST CDS_LIB pure_quanta
J 0
(-6375 4450);
DISPLAY INVISIBLE (-6375 4450);
FORCEPROP 2 LAST SEC_TYPE 0402LF
J 0
(-6325 4675);
DISPLAY 1.021277 (-6325 4675);
DISPLAY INVISIBLE (-6325 4675);
FORCEPROP 1 LAST MATERIAL CHIP
J 0
(-6335 4375);
DISPLAY 0.978723 (-6335 4375);
PAINT SKYBLUE (-6335 4375);
DISPLAY INVISIBLE (-6335 4375);
FORCEPROP 1 LAST PATH I31
J 0
(-6325 4625);
DISPLAY 0.978723 (-6325 4625);
PAINT WHITE (-6325 4625);
DISPLAY INVISIBLE (-6325 4625);
FORCEPROP 1 LAST PART_NUMBER CS31002JB08
J 0
(-6325 4375);
DISPLAY 0.489362 (-6325 4375);
PAINT SKYBLUE (-6325 4375);
DISPLAY INVISIBLE (-6325 4375);
FORCEADD UNIVERSAL_POWER..1
R 2
(-6375 4750);
FORCEPROP 3 LASTPIN (-6375 4700) SIG_NAME PVDD_33_S5_VCC\g
J 0
(-6365 4710);
DISPLAY 0.659574 (-6365 4710);
PAINT MONO (-6365 4710);
DISPLAY INVISIBLE (-6365 4710);
FORCEPROP 1 LAST HDL_POWER PVDD_33_S5_VCC
J 1
(-6375 4800);
DISPLAY 0.489362 (-6375 4800);
PAINT GREEN (-6375 4800);
FORCEPROP 2 LAST CDS_LIB pure_quanta_power
J 0
(-6375 4750);
DISPLAY INVISIBLE (-6375 4750);
FORCEPROP 1 LAST PATH I32
J 2
(-6425 4775);
DISPLAY 0.872340 (-6425 4775);
PAINT AQUA (-6425 4775);
DISPLAY INVISIBLE (-6425 4775);
FORCEADD Q_RES..1
(-5225 4100);
FORCEPROP 1 LAST LOCATION R225
J 0
(-5100 4100);
DISPLAY 0.489362 (-5100 4100);
PAINT SKYBLUE (-5100 4100);
FORCEPROP 0 LAST $SEC 1
J 0
(-5100 4150);
DISPLAY 0.680851 (-5100 4150);
PAINT MONO (-5100 4150);
DISPLAY INVISIBLE (-5100 4150);
FORCEPROP 0 LAST CDS_SEC 1
J 0
(-5100 4150);
DISPLAY 1.021277 (-5100 4150);
DISPLAY INVISIBLE (-5100 4150);
FORCEPROP 1 LASTPIN (-5325 4100) $PN 1
J 0
(-5313 4112);
DISPLAY 0.489362 (-5313 4112);
PAINT MONO (-5313 4112);
FORCEPROP 1 LASTPIN (-5125 4100) $PN 2
J 0
(-5163 4112);
DISPLAY 0.489362 (-5163 4112);
PAINT MONO (-5163 4112);
FORCEPROP 1 LAST VALUE 33
J 2
(-5350 4100);
DISPLAY 0.489362 (-5350 4100);
PAINT SKYBLUE (-5350 4100);
FORCEPROP 1 LAST PACK_TYPE 0402LF
J 2
(-5050 4025);
DISPLAY 0.489362 (-5050 4025);
PAINT SKYBLUE (-5050 4025);
DISPLAY INVISIBLE (-5050 4025);
FORCEPROP 1 LAST TOLERANCE 5%
J 0
(-5350 4075);
DISPLAY 0.489362 (-5350 4075);
PAINT SKYBLUE (-5350 4075);
DISPLAY INVISIBLE (-5350 4075);
FORCEPROP 1 LAST MATERIAL CHIP
J 2
(-5050 4075);
DISPLAY 0.489362 (-5050 4075);
PAINT SKYBLUE (-5050 4075);
DISPLAY INVISIBLE (-5050 4075);
FORCEPROP 1 LAST WATTAGE 1/16W
J 2
(-5300 4025);
DISPLAY 0.489362 (-5300 4025);
PAINT SKYBLUE (-5300 4025);
DISPLAY INVISIBLE (-5300 4025);
FORCEPROP 2 LAST BOM_COST MEM
J 2
(-5200 4250);
DISPLAY 0.744681 (-5200 4250);
PAINT WHITE (-5200 4250);
DISPLAY INVISIBLE (-5200 4250);
FORCEPROP 2 LAST CDS_LIB pure_quanta
J 2
(-5225 4100);
DISPLAY INVISIBLE (-5225 4100);
FORCEPROP 1 LAST PATH I33
J 0
(-5275 4250);
DISPLAY 0.978723 (-5275 4250);
PAINT WHITE (-5275 4250);
DISPLAY INVISIBLE (-5275 4250);
FORCEPROP 1 LAST PART_NUMBER CS03302JB10
J 2
(-5125 4150);
DISPLAY 0.489362 (-5125 4150);
PAINT SKYBLUE (-5125 4150);
DISPLAY INVISIBLE (-5125 4150);
FORCEADD UNIVERSAL_GND..1
(-3275 2900);
FORCEPROP 3 LASTPIN (-3275 2950) SIG_NAME GND\g
J 0
(-3265 2960);
DISPLAY 0.659574 (-3265 2960);
PAINT MONO (-3265 2960);
DISPLAY INVISIBLE (-3265 2960);
FORCEPROP 2 LAST CDS_LIB pure_quanta_power
J 0
(-3275 2900);
DISPLAY INVISIBLE (-3275 2900);
FORCEPROP 1 LAST HDL_POWER GND
J 1
(-3250 2825);
DISPLAY 0.872340 (-3250 2825);
PAINT GREEN (-3250 2825);
DISPLAY INVISIBLE (-3250 2825);
FORCEPROP 1 LAST PATH I34
J 0
(-3200 2900);
DISPLAY 0.872340 (-3200 2900);
PAINT AQUA (-3200 2900);
DISPLAY INVISIBLE (-3200 2900);
FORCEADD Q_CAP..1
(-3975 3300);
FORCEPROP 1 LAST LOCATION PC134
J 0
(-3925 3400);
DISPLAY 0.489362 (-3925 3400);
PAINT SKYBLUE (-3925 3400);
FORCEPROP 2 LAST SEC 1
J 0
(-3925 3500);
DISPLAY 0.680851 (-3925 3500);
PAINT MONO (-3925 3500);
DISPLAY INVISIBLE (-3925 3500);
FORCEPROP 1 LASTPIN (-3975 3400) $PN 1
J 0
(-3965 3380);
DISPLAY 0.489362 (-3965 3380);
PAINT MONO (-3965 3380);
FORCEPROP 1 LASTPIN (-3975 3200) $PN 2
J 0
(-3965 3180);
DISPLAY 0.489362 (-3965 3180);
PAINT MONO (-3965 3180);
FORCEPROP 1 LAST TOLERANCE 20%
J 0
(-3925 3250);
DISPLAY 0.489362 (-3925 3250);
PAINT SKYBLUE (-3925 3250);
FORCEPROP 1 LAST MATERIAL X6S
J 0
(-3925 3200);
DISPLAY 0.489362 (-3925 3200);
PAINT SKYBLUE (-3925 3200);
FORCEPROP 1 LAST VALUE 22UF
J 0
(-3925 3350);
DISPLAY 0.489362 (-3925 3350);
PAINT SKYBLUE (-3925 3350);
FORCEPROP 1 LAST VOLTAGE 16V
J 0
(-3925 3300);
DISPLAY 0.489362 (-3925 3300);
PAINT SKYBLUE (-3925 3300);
FORCEPROP 1 LAST PACK_TYPE C0805
J 0
(-3925 3150);
DISPLAY 0.489362 (-3925 3150);
PAINT SKYBLUE (-3925 3150);
FORCEPROP 2 LAST SEC_TYPE C0805
J 0
(-3925 3500);
DISPLAY 1.021277 (-3925 3500);
DISPLAY INVISIBLE (-3925 3500);
FORCEPROP 2 LAST CDS_LIB pure_quanta
J 0
(-3975 3300);
DISPLAY INVISIBLE (-3975 3300);
FORCEPROP 1 LAST PATH I35
J 0
(-3925 3450);
DISPLAY 0.978723 (-3925 3450);
PAINT WHITE (-3925 3450);
DISPLAY INVISIBLE (-3925 3450);
FORCEPROP 1 LAST PART_NUMBER CH6223MEA01
J 0
(-3925 3150);
DISPLAY 0.978723 (-3925 3150);
PAINT SKYBLUE (-3925 3150);
DISPLAY INVISIBLE (-3925 3150);
FORCEADD Q_CAP..1
(-3675 3300);
FORCEPROP 1 LAST LOCATION PC135
J 0
(-3625 3400);
DISPLAY 0.489362 (-3625 3400);
PAINT SKYBLUE (-3625 3400);
FORCEPROP 2 LAST SEC 1
J 0
(-3625 3500);
DISPLAY 0.680851 (-3625 3500);
PAINT MONO (-3625 3500);
DISPLAY INVISIBLE (-3625 3500);
FORCEPROP 1 LASTPIN (-3675 3400) $PN 1
J 0
(-3665 3380);
DISPLAY 0.489362 (-3665 3380);
PAINT MONO (-3665 3380);
FORCEPROP 1 LASTPIN (-3675 3200) $PN 2
J 0
(-3665 3180);
DISPLAY 0.489362 (-3665 3180);
PAINT MONO (-3665 3180);
FORCEPROP 1 LAST MATERIAL X6S
J 0
(-3625 3200);
DISPLAY 0.489362 (-3625 3200);
PAINT SKYBLUE (-3625 3200);
FORCEPROP 1 LAST TOLERANCE 20%
J 0
(-3625 3250);
DISPLAY 0.489362 (-3625 3250);
PAINT SKYBLUE (-3625 3250);
FORCEPROP 1 LAST VALUE 22UF
J 0
(-3625 3350);
DISPLAY 0.489362 (-3625 3350);
PAINT SKYBLUE (-3625 3350);
FORCEPROP 1 LAST VOLTAGE 16V
J 0
(-3625 3300);
DISPLAY 0.489362 (-3625 3300);
PAINT SKYBLUE (-3625 3300);
FORCEPROP 1 LAST PACK_TYPE C0805
J 0
(-3625 3150);
DISPLAY 0.489362 (-3625 3150);
PAINT SKYBLUE (-3625 3150);
FORCEPROP 2 LAST SEC_TYPE C0805
J 0
(-3625 3500);
DISPLAY 1.021277 (-3625 3500);
DISPLAY INVISIBLE (-3625 3500);
FORCEPROP 2 LAST CDS_LIB pure_quanta
J 0
(-3675 3300);
DISPLAY INVISIBLE (-3675 3300);
FORCEPROP 1 LAST PATH I36
J 0
(-3625 3450);
DISPLAY 0.978723 (-3625 3450);
PAINT WHITE (-3625 3450);
DISPLAY INVISIBLE (-3625 3450);
FORCEPROP 1 LAST PART_NUMBER CH6223MEA01
J 0
(-3625 3100);
DISPLAY 0.489362 (-3625 3100);
PAINT SKYBLUE (-3625 3100);
DISPLAY INVISIBLE (-3625 3100);
FORCEADD Q_CAP..1
(-3275 3300);
FORCEPROP 1 LAST LOCATION PC136
J 0
(-3225 3400);
DISPLAY 0.489362 (-3225 3400);
PAINT SKYBLUE (-3225 3400);
FORCEPROP 2 LAST SEC 1
J 0
(-3225 3500);
DISPLAY 0.680851 (-3225 3500);
PAINT MONO (-3225 3500);
DISPLAY INVISIBLE (-3225 3500);
FORCEPROP 1 LASTPIN (-3275 3400) $PN 1
J 0
(-3265 3380);
DISPLAY 0.489362 (-3265 3380);
PAINT MONO (-3265 3380);
FORCEPROP 1 LASTPIN (-3275 3200) $PN 2
J 0
(-3265 3180);
DISPLAY 0.489362 (-3265 3180);
PAINT MONO (-3265 3180);
FORCEPROP 1 LAST PACK_TYPE 0402
J 0
(-3225 3100);
DISPLAY 0.489362 (-3225 3100);
PAINT SKYBLUE (-3225 3100);
FORCEPROP 1 LAST VOLTAGE 25V
J 0
(-3225 3300);
DISPLAY 0.489362 (-3225 3300);
PAINT SKYBLUE (-3225 3300);
FORCEPROP 1 LAST MATERIAL X7R
J 0
(-3225 3200);
DISPLAY 0.489362 (-3225 3200);
PAINT SKYBLUE (-3225 3200);
FORCEPROP 1 LAST VALUE 0.1UF
J 0
(-3225 3350);
DISPLAY 0.489362 (-3225 3350);
PAINT SKYBLUE (-3225 3350);
FORCEPROP 1 LAST TOLERANCE 10%
J 0
(-3225 3250);
DISPLAY 0.489362 (-3225 3250);
PAINT SKYBLUE (-3225 3250);
FORCEPROP 2 LAST CDS_LIB pure_quanta
J 0
(-3275 3300);
DISPLAY INVISIBLE (-3275 3300);
FORCEPROP 2 LAST SEC_TYPE 0402
J 0
(-3225 3500);
DISPLAY 1.021277 (-3225 3500);
DISPLAY INVISIBLE (-3225 3500);
FORCEPROP 1 LAST PATH I37
J 0
(-3225 3450);
DISPLAY 0.978723 (-3225 3450);
PAINT WHITE (-3225 3450);
DISPLAY INVISIBLE (-3225 3450);
FORCEPROP 1 LAST PART_NUMBER CH4104K1B00
J 0
(-3225 3150);
DISPLAY 0.489362 (-3225 3150);
PAINT SKYBLUE (-3225 3150);
DISPLAY INVISIBLE (-3225 3150);
FORCEADD UNIVERSAL_POWER..1
(-2825 3750);
FORCEPROP 3 LASTPIN (-2825 3700) SIG_NAME PVDD_33_S5\g
J 0
(-2815 3710);
DISPLAY 0.659574 (-2815 3710);
PAINT MONO (-2815 3710);
DISPLAY INVISIBLE (-2815 3710);
FORCEPROP 1 LAST HDL_POWER PVDD_33_S5
J 1
(-2825 3800);
DISPLAY 0.489362 (-2825 3800);
PAINT GREEN (-2825 3800);
FORCEPROP 2 LAST CDS_LIB pure_quanta_power
J 0
(-2825 3750);
DISPLAY INVISIBLE (-2825 3750);
FORCEPROP 1 LAST PATH I38
J 0
(-2775 3775);
DISPLAY 0.872340 (-2775 3775);
PAINT AQUA (-2775 3775);
DISPLAY INVISIBLE (-2775 3775);
FORCEADD OFFPAGE..2
(-4175 4100);
FORCEPROP 2 LAST $XR0 81 
J 0
(-3986 4100);
DISPLAY 0.638298 (-3986 4100);
PAINT MONO (-3986 4100);
FORCEPROP 2 LAST CDS_LIB standard
J 0
(-4175 4100);
DISPLAY INVISIBLE (-4175 4100);
FORCEPROP 1 LAST OFFPAGE TRUE
J 0
(-3850 3975);
DISPLAY 0.872340 (-3850 3975);
PAINT GREEN (-3850 3975);
DISPLAY INVISIBLE (-3850 3975);
FORCEPROP 1 LAST COMMENT_BODY TRUE
J 0
(-4220 4005);
DISPLAY 0.872340 (-4220 4005);
PAINT GREEN (-4220 4005);
DISPLAY INVISIBLE (-4220 4005);
FORCEPROP 2 LAST PATH I39
J 0
(-3975 4150);
DISPLAY 0.680851 (-3975 4150);
DISPLAY INVISIBLE (-3975 4150);
FORCEADD UNIVERSAL_POWER..1
(-8450 3050);
FORCEPROP 3 LASTPIN (-8450 3000) SIG_NAME PVDD_33_S5_VCC\g
J 0
(-8440 3010);
DISPLAY 0.659574 (-8440 3010);
PAINT MONO (-8440 3010);
DISPLAY INVISIBLE (-8440 3010);
FORCEPROP 1 LAST HDL_POWER PVDD_33_S5_VCC
J 1
(-8450 3100);
DISPLAY 0.489362 (-8450 3100);
PAINT GREEN (-8450 3100);
FORCEPROP 2 LAST CDS_LIB pure_quanta_power
J 0
(-8450 3050);
DISPLAY INVISIBLE (-8450 3050);
FORCEPROP 1 LAST PATH I4
J 0
(-8400 3075);
DISPLAY 0.872340 (-8400 3075);
PAINT AQUA (-8400 3075);
DISPLAY INVISIBLE (-8400 3075);
FORCEADD Q_CAP..1
(-5425 3725);
FORCEPROP 1 LAST LOCATION PC128
J 0
(-5375 3850);
DISPLAY 0.489362 (-5375 3850);
PAINT SKYBLUE (-5375 3850);
FORCEPROP 0 LAST SEC 1
J 0
(-5375 3875);
DISPLAY 0.680851 (-5375 3875);
PAINT MONO (-5375 3875);
DISPLAY INVISIBLE (-5375 3875);
FORCEPROP 1 LASTPIN (-5425 3825) $PN 1
J 0
(-5415 3805);
DISPLAY 0.489362 (-5415 3805);
PAINT MONO (-5415 3805);
FORCEPROP 1 LASTPIN (-5425 3625) $PN 2
J 0
(-5415 3605);
DISPLAY 0.489362 (-5415 3605);
PAINT MONO (-5415 3605);
FORCEPROP 1 LAST VOLTAGE 25V
J 0
(-5375 3750);
DISPLAY 0.489362 (-5375 3750);
PAINT SKYBLUE (-5375 3750);
FORCEPROP 1 LAST VALUE 0.1UF
J 0
(-5375 3800);
DISPLAY 0.489362 (-5375 3800);
PAINT SKYBLUE (-5375 3800);
FORCEPROP 1 LAST PACK_TYPE 0402
J 0
(-5375 3625);
DISPLAY 0.489362 (-5375 3625);
PAINT SKYBLUE (-5375 3625);
FORCEPROP 1 LAST MATERIAL X7R
J 0
(-5375 3700);
DISPLAY 0.489362 (-5375 3700);
PAINT SKYBLUE (-5375 3700);
FORCEPROP 1 LAST TOLERANCE 10%
J 0
(-5375 3675);
DISPLAY 0.978723 (-5375 3675);
PAINT SKYBLUE (-5375 3675);
DISPLAY INVISIBLE (-5375 3675);
FORCEPROP 2 LAST SEC_TYPE 0402
J 0
(-5375 3925);
DISPLAY 1.021277 (-5375 3925);
DISPLAY INVISIBLE (-5375 3925);
FORCEPROP 2 LAST CDS_LIB pure_quanta
J 0
(-5425 3725);
DISPLAY INVISIBLE (-5425 3725);
FORCEPROP 1 LAST PATH I40
J 0
(-5375 3875);
DISPLAY 0.978723 (-5375 3875);
PAINT WHITE (-5375 3875);
DISPLAY INVISIBLE (-5375 3875);
FORCEPROP 1 LAST PART_NUMBER CH4104K1B00
J 0
(-5375 3650);
DISPLAY 0.489362 (-5375 3650);
PAINT SKYBLUE (-5375 3650);
DISPLAY INVISIBLE (-5375 3650);
FORCEADD MPQ8633AGLEC807Z..1
(-6875 3425);
FORCEPROP 1 LAST LOCATION PU55
J 0
(-7125 4397);
DISPLAY 0.489362 (-7125 4397);
PAINT SKYBLUE (-7125 4397);
FORCEPROP 0 LAST SEC 1
J 0
(-7125 4425);
DISPLAY 0.680851 (-7125 4425);
PAINT MONO (-7125 4425);
DISPLAY INVISIBLE (-7125 4425);
FORCEPROP 0 LASTPIN (-6475 2750) $PN 2
J 0
(-6465 2760);
DISPLAY 0.489362 (-6465 2760);
PAINT MONO (-6465 2760);
FORCEPROP 0 LASTPIN (-6475 3900) $PN 1
J 0
(-6465 3910);
DISPLAY 0.489362 (-6465 3910);
PAINT MONO (-6465 3910);
FORCEPROP 0 LASTPIN (-7275 2800) $PN 3
J 2
(-7285 2810);
DISPLAY 0.489362 (-7285 2810);
PAINT MONO (-7285 2810);
FORCEPROP 0 LASTPIN (-7275 3600) $PN 8
J 2
(-7285 3610);
DISPLAY 0.489362 (-7285 3610);
PAINT MONO (-7285 3610);
FORCEPROP 0 LASTPIN (-6475 3150) $PN 7
J 0
(-6465 3160);
DISPLAY 0.489362 (-6465 3160);
PAINT MONO (-6465 3160);
FORCEPROP 0 LASTPIN (-7275 3400) $PN 4
J 2
(-7285 3410);
DISPLAY 0.489362 (-7285 3410);
PAINT MONO (-7285 3410);
FORCEPROP 0 LASTPIN (-6475 2800) $PN 11_18
J 0
(-6465 2810);
DISPLAY 0.489362 (-6465 2810);
PAINT MONO (-6465 2810);
FORCEPROP 0 LASTPIN (-6475 4100) $PN 9
J 0
(-6465 4110);
DISPLAY 0.489362 (-6465 4110);
PAINT MONO (-6465 4110);
FORCEPROP 0 LASTPIN (-6475 3000) $PN 6
J 0
(-6465 3010);
DISPLAY 0.489362 (-6465 3010);
PAINT MONO (-6465 3010);
FORCEPROP 0 LASTPIN (-6475 3600) $PN 20
J 0
(-6465 3610);
DISPLAY 0.489362 (-6465 3610);
PAINT MONO (-6465 3610);
FORCEPROP 0 LASTPIN (-6475 2900) $PN 5
J 0
(-6465 2910);
DISPLAY 0.489362 (-6465 2910);
PAINT MONO (-6465 2910);
FORCEPROP 0 LASTPIN (-7275 3150) $PN 19
J 2
(-7285 3160);
DISPLAY 0.489362 (-7285 3160);
PAINT MONO (-7285 3160);
FORCEPROP 0 LASTPIN (-7275 4100) $PN 10
J 2
(-7285 4110);
DISPLAY 0.489362 (-7285 4110);
PAINT MONO (-7285 4110);
FORCEPROP 0 LASTPIN (-7275 4050) $PN 21
J 2
(-7285 4060);
DISPLAY 0.489362 (-7285 4060);
PAINT MONO (-7285 4060);
FORCEPROP 1 LAST MATERIAL IC
J 0
(-7122 4190);
DISPLAY 0.489362 (-7122 4190);
PAINT SKYBLUE (-7122 4190);
FORCEPROP 2 LAST VALUE MPQ8633AGLE-C807-Z
J 0
(-7128 4333);
DISPLAY 0.489362 (-7128 4333);
PAINT SKYBLUE (-7128 4333);
FORCEPROP 2 LAST SEC_TYPE 
J 0
(-7125 4425);
DISPLAY 1.021277 (-7125 4425);
DISPLAY INVISIBLE (-7125 4425);
FORCEPROP 1 LAST NEEDS_NO_SIZE TRUE
J 0
(-6875 3425);
DISPLAY 0.723404 (-6875 3425);
PAINT GREEN (-6875 3425);
DISPLAY INVISIBLE (-6875 3425);
FORCEPROP 0 LAST PART_TYPE SMLF
J 0
(-7100 4425);
DISPLAY 1.021277 (-7100 4425);
DISPLAY INVISIBLE (-7100 4425);
FORCEPROP 1 LAST CDS_LMAN_SYM_OUTLINE -250,725,250,-725
J 0
(-6875 3425);
DISPLAY 0.468085 (-6875 3425);
PAINT GREEN (-6875 3425);
DISPLAY INVISIBLE (-6875 3425);
FORCEPROP 2 LAST CDS_LIB pure_quanta
J 0
(-6875 3425);
DISPLAY INVISIBLE (-6875 3425);
FORCEPROP 1 LAST PATH I41
J 0
(-6875 3425);
DISPLAY 0.723404 (-6875 3425);
PAINT GREEN (-6875 3425);
DISPLAY INVISIBLE (-6875 3425);
FORCEPROP 1 LAST PART_NUMBER AL008633007
J 0
(-7125 4250);
DISPLAY 0.489362 (-7125 4250);
PAINT SKYBLUE (-7125 4250);
DISPLAY INVISIBLE (-7125 4250);
FORCEADD UNIVERSAL_GND..1
(-4850 3750);
FORCEPROP 3 LASTPIN (-4850 3800) SIG_NAME GND\g
J 0
(-4840 3810);
DISPLAY 0.659574 (-4840 3810);
PAINT MONO (-4840 3810);
DISPLAY INVISIBLE (-4840 3810);
FORCEPROP 2 LAST CDS_LIB pure_quanta_power
J 0
(-4850 3750);
DISPLAY INVISIBLE (-4850 3750);
FORCEPROP 1 LAST HDL_POWER GND
J 1
(-4825 3675);
DISPLAY 0.872340 (-4825 3675);
PAINT GREEN (-4825 3675);
DISPLAY INVISIBLE (-4825 3675);
FORCEPROP 1 LAST PATH I42
J 0
(-4775 3750);
DISPLAY 0.872340 (-4775 3750);
PAINT AQUA (-4775 3750);
DISPLAY INVISIBLE (-4775 3750);
FORCEADD Q_CAP..1
(-4850 3950);
FORCEPROP 1 LAST LOCATION C5002
J 0
(-4800 4050);
DISPLAY 0.638298 (-4800 4050);
FORCEPROP 0 LAST $SEC 1
J 0
(-4800 4100);
DISPLAY 0.680851 (-4800 4100);
PAINT MONO (-4800 4100);
DISPLAY INVISIBLE (-4800 4100);
FORCEPROP 0 LAST CDS_SEC 1
J 0
(-4800 4100);
DISPLAY 0.680851 (-4800 4100);
DISPLAY INVISIBLE (-4800 4100);
FORCEPROP 1 LASTPIN (-4850 4050) $PN 1
J 0
(-4840 4030);
DISPLAY 0.787234 (-4840 4030);
PAINT MONO (-4840 4030);
FORCEPROP 1 LASTPIN (-4850 3850) $PN 2
J 0
(-4840 3830);
DISPLAY 0.787234 (-4840 3830);
PAINT MONO (-4840 3830);
FORCEPROP 1 LAST PACK_TYPE 0402
J 0
(-4800 3750);
DISPLAY 0.638298 (-4800 3750);
FORCEPROP 1 LAST VOLTAGE 50V
J 0
(-4800 3950);
DISPLAY 0.638298 (-4800 3950);
FORCEPROP 1 LAST VALUE 1000PF
J 0
(-4800 4000);
DISPLAY 0.638298 (-4800 4000);
FORCEPROP 1 LAST MATERIAL X7R
J 0
(-4800 3850);
DISPLAY 0.638298 (-4800 3850);
FORCEPROP 1 LAST TOLERANCE 5%
J 0
(-4800 3900);
DISPLAY 0.638298 (-4800 3900);
FORCEPROP 2 LAST CDS_LIB pure_quanta
J 0
(-4850 3950);
DISPLAY INVISIBLE (-4850 3950);
FORCEPROP 1 LAST PATH I43
J 0
(-4800 4100);
DISPLAY 0.978723 (-4800 4100);
PAINT WHITE (-4800 4100);
DISPLAY INVISIBLE (-4800 4100);
FORCEPROP 1 LAST PART_NUMBER TMP_QCH21006JB10
J 0
(-4800 3800);
DISPLAY 0.638298 (-4800 3800);
DISPLAY INVISIBLE (-4800 3800);
FORCEADD Q_CAP..1
(-9275 4500);
FORCEPROP 1 LAST LOCATION PC8000
J 0
(-9225 4600);
DISPLAY 0.638298 (-9225 4600);
FORCEPROP 0 LAST $SEC 1
J 0
(-9225 4650);
DISPLAY 0.680851 (-9225 4650);
PAINT MONO (-9225 4650);
DISPLAY INVISIBLE (-9225 4650);
FORCEPROP 0 LAST CDS_SEC 1
J 0
(-9225 4650);
DISPLAY 0.680851 (-9225 4650);
DISPLAY INVISIBLE (-9225 4650);
FORCEPROP 1 LASTPIN (-9275 4600) $PN 1
J 0
(-9265 4580);
DISPLAY 0.787234 (-9265 4580);
PAINT MONO (-9265 4580);
FORCEPROP 1 LASTPIN (-9275 4400) $PN 2
J 0
(-9265 4380);
DISPLAY 0.787234 (-9265 4380);
PAINT MONO (-9265 4380);
FORCEPROP 1 LAST PACK_TYPE C0805
J 0
(-9225 4300);
DISPLAY 0.510638 (-9225 4300);
FORCEPROP 1 LAST TOLERANCE 20%
J 0
(-9225 4450);
DISPLAY 0.510638 (-9225 4450);
FORCEPROP 1 LAST MATERIAL X6S
J 0
(-9225 4400);
DISPLAY 0.510638 (-9225 4400);
FORCEPROP 1 LAST VALUE 22UF
J 0
(-9225 4550);
DISPLAY 0.510638 (-9225 4550);
FORCEPROP 1 LAST VOLTAGE 16V
J 0
(-9225 4500);
DISPLAY 0.510638 (-9225 4500);
FORCEPROP 2 LAST CDS_LIB pure_quanta
J 0
(-9275 4500);
DISPLAY INVISIBLE (-9275 4500);
FORCEPROP 1 LAST PATH I44
J 0
(-9225 4650);
DISPLAY 0.978723 (-9225 4650);
PAINT WHITE (-9225 4650);
DISPLAY INVISIBLE (-9225 4650);
FORCEPROP 1 LAST PART_NUMBER CH6223MEA01
J 0
(-9225 4350);
DISPLAY 0.510638 (-9225 4350);
DISPLAY INVISIBLE (-9225 4350);
FORCEADD Q_CAP..1
(-9600 4500);
FORCEPROP 1 LAST LOCATION PC8001
J 0
(-9550 4600);
DISPLAY 0.638298 (-9550 4600);
FORCEPROP 0 LAST $SEC 1
J 0
(-9550 4650);
DISPLAY 0.680851 (-9550 4650);
PAINT MONO (-9550 4650);
DISPLAY INVISIBLE (-9550 4650);
FORCEPROP 0 LAST CDS_SEC 1
J 0
(-9550 4650);
DISPLAY 0.680851 (-9550 4650);
DISPLAY INVISIBLE (-9550 4650);
FORCEPROP 1 LASTPIN (-9600 4600) $PN 1
J 0
(-9590 4580);
DISPLAY 0.787234 (-9590 4580);
PAINT MONO (-9590 4580);
FORCEPROP 1 LASTPIN (-9600 4400) $PN 2
J 0
(-9590 4380);
DISPLAY 0.787234 (-9590 4380);
PAINT MONO (-9590 4380);
FORCEPROP 1 LAST MATERIAL X6S
J 0
(-9550 4400);
DISPLAY 0.510638 (-9550 4400);
FORCEPROP 1 LAST VOLTAGE 16V
J 0
(-9550 4500);
DISPLAY 0.510638 (-9550 4500);
FORCEPROP 1 LAST TOLERANCE 20%
J 0
(-9550 4450);
DISPLAY 0.510638 (-9550 4450);
FORCEPROP 1 LAST VALUE 22UF
J 0
(-9550 4550);
DISPLAY 0.510638 (-9550 4550);
FORCEPROP 1 LAST PACK_TYPE C0805
J 0
(-9550 4300);
DISPLAY 0.510638 (-9550 4300);
FORCEPROP 2 LAST CDS_LIB pure_quanta
J 0
(-9600 4500);
DISPLAY INVISIBLE (-9600 4500);
FORCEPROP 1 LAST PATH I45
J 0
(-9550 4650);
DISPLAY 0.978723 (-9550 4650);
PAINT WHITE (-9550 4650);
DISPLAY INVISIBLE (-9550 4650);
FORCEPROP 1 LAST PART_NUMBER CH6223MEA01
J 0
(-9550 4350);
DISPLAY 0.510638 (-9550 4350);
DISPLAY INVISIBLE (-9550 4350);
FORCEADD Q_RES..1
(-5750 3900);
FORCEPROP 1 LAST LOCATION PR8000
J 0
(-5800 3950);
DISPLAY 0.510638 (-5800 3950);
FORCEPROP 0 LAST $SEC 1
J 0
(-5875 4000);
DISPLAY 0.680851 (-5875 4000);
PAINT MONO (-5875 4000);
DISPLAY INVISIBLE (-5875 4000);
FORCEPROP 0 LAST CDS_SEC 1
J 0
(-5875 4000);
DISPLAY 0.680851 (-5875 4000);
DISPLAY INVISIBLE (-5875 4000);
FORCEPROP 1 LASTPIN (-5850 3900) $PN 1
J 0
(-5838 3912);
DISPLAY 0.787234 (-5838 3912);
PAINT MONO (-5838 3912);
FORCEPROP 1 LASTPIN (-5650 3900) $PN 2
J 0
(-5688 3912);
DISPLAY 0.787234 (-5688 3912);
PAINT MONO (-5688 3912);
FORCEPROP 1 LAST WATTAGE 1/16W
J 2
(-5775 3800);
DISPLAY 0.510638 (-5775 3800);
FORCEPROP 1 LAST MATERIAL CHIP
J 0
(-5750 3800);
DISPLAY 0.510638 (-5750 3800);
FORCEPROP 1 LAST VALUE 0
J 2
(-5825 3850);
DISPLAY 0.510638 (-5825 3850);
FORCEPROP 1 LAST TOLERANCE 5%
J 0
(-5800 3850);
DISPLAY 0.510638 (-5800 3850);
FORCEPROP 1 LAST PACK_TYPE 0402LF
J 0
(-5675 3850);
DISPLAY 0.510638 (-5675 3850);
FORCEPROP 2 LAST CDS_LIB pure_quanta
J 0
(-5750 3900);
DISPLAY INVISIBLE (-5750 3900);
FORCEPROP 1 LAST PATH I46
J 0
(-5800 4050);
DISPLAY 0.978723 (-5800 4050);
PAINT WHITE (-5800 4050);
DISPLAY INVISIBLE (-5800 4050);
FORCEPROP 1 LAST PART_NUMBER CS00002JB13
J 0
(-5875 3975);
DISPLAY 0.510638 (-5875 3975);
DISPLAY INVISIBLE (-5875 3975);
FORCEADD Q_INDUCTOR..1
(-4850 3625);
FORCEPROP 1 LAST LOCATION PL72
J 0
(-4875 3650);
DISPLAY 0.468085 (-4875 3650);
PAINT GREEN (-4875 3650);
FORCEPROP 2 LAST SEC 1
J 0
(-4975 3900);
DISPLAY 0.680851 (-4975 3900);
PAINT MONO (-4975 3900);
DISPLAY INVISIBLE (-4975 3900);
FORCEPROP 2 LASTPIN (-4950 3600) $PN 1
J 2
(-4960 3610);
DISPLAY 0.680851 (-4960 3610);
PAINT MONO (-4960 3610);
FORCEPROP 2 LASTPIN (-4750 3600) $PN 2
J 0
(-4740 3610);
DISPLAY 0.680851 (-4740 3610);
PAINT MONO (-4740 3610);
FORCEPROP 2 LAST VALUE 1.5UH
J 0
(-5075 3650);
DISPLAY 0.446809 (-5075 3650);
FORCEPROP 2 LAST PACK_TYPE SMLF
J 0
(-4750 3650);
DISPLAY 0.446809 (-4750 3650);
FORCEPROP 1 LAST MATERIAL IND
J 0
(-4775 3575);
DISPLAY 0.468085 (-4775 3575);
PAINT GREEN (-4775 3575);
FORCEPROP 2 LAST CDS_LIB pure_quanta
J 0
(-4850 3625);
DISPLAY INVISIBLE (-4850 3625);
FORCEPROP 1 LAST NEEDS_NO_SIZE TRUE
J 0
(-4850 3625);
DISPLAY 0.468085 (-4850 3625);
PAINT GREEN (-4850 3625);
DISPLAY INVISIBLE (-4850 3625);
FORCEPROP 2 LAST SEC_TYPE SMLF
J 0
(-4975 3900);
DISPLAY 0.680851 (-4975 3900);
DISPLAY INVISIBLE (-4975 3900);
FORCEPROP 1 LAST PATH I47
J 0
(-4775 3680);
DISPLAY 0.723404 (-4775 3680);
PAINT GREEN (-4775 3680);
DISPLAY INVISIBLE (-4775 3680);
FORCEPROP 1 LAST PART_NUMBER CV-15I0MZ28
J 0
(-5150 3575);
DISPLAY 0.468085 (-5150 3575);
PAINT GREEN (-5150 3575);
DISPLAY INVISIBLE (-5150 3575);
FORCEADD Q_CAP..1
R 2
(-8475 3425);
FORCEPROP 1 LAST LOCATION C348
J 2
(-8525 3525);
DISPLAY 0.489362 (-8525 3525);
PAINT SKYBLUE (-8525 3525);
FORCEPROP 0 LAST $SEC 1
J 0
(-8525 3575);
DISPLAY 0.680851 (-8525 3575);
PAINT MONO (-8525 3575);
DISPLAY INVISIBLE (-8525 3575);
FORCEPROP 0 LAST CDS_SEC 1
J 0
(-8525 3575);
DISPLAY 0.680851 (-8525 3575);
DISPLAY INVISIBLE (-8525 3575);
FORCEPROP 1 LASTPIN (-8475 3525) $PN 1
J 2
(-8485 3505);
DISPLAY 0.489362 (-8485 3505);
PAINT MONO (-8485 3505);
FORCEPROP 1 LASTPIN (-8475 3325) $PN 2
J 2
(-8485 3305);
DISPLAY 0.489362 (-8485 3305);
PAINT MONO (-8485 3305);
FORCEPROP 1 LAST VALUE 0.1UF
J 2
(-8525 3475);
DISPLAY 0.489362 (-8525 3475);
PAINT SKYBLUE (-8525 3475);
FORCEPROP 1 LAST PACK_TYPE 0402
J 2
(-8525 3225);
DISPLAY 0.489362 (-8525 3225);
PAINT SKYBLUE (-8525 3225);
FORCEPROP 1 LAST VOLTAGE 25V
J 2
(-8525 3425);
DISPLAY 0.489362 (-8525 3425);
PAINT SKYBLUE (-8525 3425);
FORCEPROP 1 LAST TOLERANCE 10%
J 2
(-8525 3375);
DISPLAY 0.489362 (-8525 3375);
PAINT SKYBLUE (-8525 3375);
FORCEPROP 1 LAST MATERIAL EMPTY
J 2
(-8525 3325);
DISPLAY 0.489362 (-8525 3325);
PAINT RED (-8525 3325);
FORCEPROP 2 LAST CDS_LIB pure_quanta
J 0
(-8475 3425);
DISPLAY INVISIBLE (-8475 3425);
FORCEPROP 1 LAST PATH I5
J 2
(-8525 3575);
DISPLAY 0.978723 (-8525 3575);
PAINT WHITE (-8525 3575);
DISPLAY INVISIBLE (-8525 3575);
FORCEPROP 1 LAST PART_NUMBER CH4104K1B00
J 2
(-8550 3275);
DISPLAY 0.489362 (-8550 3275);
PAINT SKYBLUE (-8550 3275);
DISPLAY INVISIBLE (-8550 3275);
FORCEADD UNIVERSAL_GND..1
(-8475 3225);
FORCEPROP 3 LASTPIN (-8475 3275) SIG_NAME GND\g
J 0
(-8465 3285);
DISPLAY 0.659574 (-8465 3285);
PAINT MONO (-8465 3285);
DISPLAY INVISIBLE (-8465 3285);
FORCEPROP 2 LAST CDS_LIB pure_quanta_power
J 0
(-8475 3225);
DISPLAY INVISIBLE (-8475 3225);
FORCEPROP 1 LAST HDL_POWER GND
J 1
(-8450 3150);
DISPLAY 0.872340 (-8450 3150);
PAINT GREEN (-8450 3150);
DISPLAY INVISIBLE (-8450 3150);
FORCEPROP 1 LAST PATH I6
J 0
(-8400 3225);
DISPLAY 0.872340 (-8400 3225);
PAINT AQUA (-8400 3225);
DISPLAY INVISIBLE (-8400 3225);
FORCEADD UNIVERSAL_GND..1
(-10550 4125);
FORCEPROP 3 LASTPIN (-10550 4175) SIG_NAME GND\g
J 0
(-10540 4185);
DISPLAY 0.659574 (-10540 4185);
PAINT MONO (-10540 4185);
DISPLAY INVISIBLE (-10540 4185);
FORCEPROP 2 LAST CDS_LIB pure_quanta_power
J 0
(-10550 4125);
DISPLAY INVISIBLE (-10550 4125);
FORCEPROP 1 LAST HDL_POWER GND
J 1
(-10525 4050);
DISPLAY 0.872340 (-10525 4050);
PAINT GREEN (-10525 4050);
DISPLAY INVISIBLE (-10525 4050);
FORCEPROP 1 LAST PATH I7
J 0
(-10475 4125);
DISPLAY 0.872340 (-10475 4125);
PAINT AQUA (-10475 4125);
DISPLAY INVISIBLE (-10475 4125);
FORCEADD Q_CAP..1
(-10550 4450);
FORCEPROP 1 LAST LOCATION PC6000
J 0
(-10500 4550);
DISPLAY 0.489362 (-10500 4550);
PAINT SKYBLUE (-10500 4550);
FORCEPROP 0 LAST $SEC 1
J 0
(-10500 4575);
DISPLAY 0.680851 (-10500 4575);
PAINT MONO (-10500 4575);
DISPLAY INVISIBLE (-10500 4575);
FORCEPROP 0 LAST CDS_SEC 1
J 0
(-10500 4575);
DISPLAY 0.680851 (-10500 4575);
DISPLAY INVISIBLE (-10500 4575);
FORCEPROP 1 LASTPIN (-10550 4550) $PN 1
J 0
(-10540 4530);
DISPLAY 0.787234 (-10540 4530);
PAINT MONO (-10540 4530);
FORCEPROP 1 LASTPIN (-10550 4350) $PN 2
J 0
(-10540 4330);
DISPLAY 0.787234 (-10540 4330);
PAINT MONO (-10540 4330);
FORCEPROP 1 LAST TOLERANCE 10%
J 0
(-10500 4400);
DISPLAY 0.489362 (-10500 4400);
PAINT SKYBLUE (-10500 4400);
FORCEPROP 1 LAST VALUE 0.1UF
J 0
(-10500 4500);
DISPLAY 0.489362 (-10500 4500);
PAINT SKYBLUE (-10500 4500);
FORCEPROP 1 LAST MATERIAL X6S
J 0
(-10500 4350);
DISPLAY 0.489362 (-10500 4350);
PAINT SKYBLUE (-10500 4350);
FORCEPROP 1 LAST VOLTAGE 25V
J 0
(-10500 4450);
DISPLAY 0.489362 (-10500 4450);
PAINT SKYBLUE (-10500 4450);
FORCEPROP 1 LAST PACK_TYPE C0402
J 0
(-10500 4250);
DISPLAY 0.489362 (-10500 4250);
PAINT SKYBLUE (-10500 4250);
FORCEPROP 2 LAST CDS_LIB pure_quanta
J 0
(-10550 4450);
DISPLAY INVISIBLE (-10550 4450);
FORCEPROP 1 LAST PATH I8
J 0
(-10500 4600);
DISPLAY 0.978723 (-10500 4600);
PAINT WHITE (-10500 4600);
DISPLAY INVISIBLE (-10500 4600);
FORCEPROP 1 LAST PART_NUMBER CH4104KEB00
J 0
(-10500 4300);
DISPLAY 0.489362 (-10500 4300);
PAINT SKYBLUE (-10500 4300);
DISPLAY INVISIBLE (-10500 4300);
FORCEADD UNIVERSAL_POWER..1
(-10450 4850);
FORCEPROP 3 LASTPIN (-10450 4800) SIG_NAME P12V_AUX\g
J 0
(-10440 4810);
DISPLAY 0.659574 (-10440 4810);
PAINT MONO (-10440 4810);
DISPLAY INVISIBLE (-10440 4810);
FORCEPROP 1 LAST HDL_POWER P12V_AUX
J 1
(-10450 4900);
DISPLAY 0.489362 (-10450 4900);
PAINT GREEN (-10450 4900);
FORCEPROP 2 LAST CDS_LIB pure_quanta_power
J 0
(-10450 4850);
DISPLAY INVISIBLE (-10450 4850);
FORCEPROP 1 LAST PATH I9
J 0
(-10400 4875);
DISPLAY 0.872340 (-10400 4875);
PAINT AQUA (-10400 4875);
DISPLAY INVISIBLE (-10400 4875);
FORCEADD QUANTA_TITLE_BLOCK_C..1
(-1675 425);
FORCEPROP 0 LAST CDS_CON_LAST_MODIFIED Thu Sep 14 16:12:40 2023
J 0
(-3560 440);
DISPLAY INVISIBLE (-3560 440);
FORCEPROP 1 LAST CUSTOM_TXT_CDS <CON_LAST_MODIFIED>
J 0
(-3560 440);
DISPLAY 0.978723 (-3560 440);
FORCEPROP 2 LAST CUSTOM_TXT_CDS <XR_PAGE_TITLE>
J 0
(-9565 5675);
DISPLAY 0.638298 (-9565 5675);
PAINT PINK (-9565 5675);
DISPLAY INVISIBLE (-9565 5675);
FORCEPROP 1 LAST CUSTOM_TXT_CDS <NAME_2>
J 0
(-4850 475);
FORCEPROP 1 LAST CUSTOM_TXT_CDS <NAME_1>
J 0
(-4850 600);
FORCEPROP 1 LAST CUSTOM_TXT_CDS <Q_NUMBER>
J 0
(-3078 528);
DISPLAY 1.212766 (-3078 528);
FORCEPROP 1 LAST CUSTOM_TXT_CDS <Q_PROJ>
J 0
(-4057 527);
DISPLAY 1.212766 (-4057 527);
FORCEPROP 1 LAST CUSTOM_TXT_CDS <Q_REV>
J 0
(-1859 528);
DISPLAY 1.212766 (-1859 528);
FORCEPROP 1 LAST CUSTOM_TXT_CDS <CON_PAGE_NUM> OF <CON_TOTAL_PAGES>
J 0
(-2121 443);
DISPLAY 0.978723 (-2121 443);
FORCEPROP 1 LAST Q_TITLE PVDD_33_S5
J 0
(-11041 451);
DISPLAY 2.446809 (-11041 451);
PAINT GREEN (-11041 451);
FORCEPROP 2 LAST PAGE_BORDER TRUE
J 0
(-9565 5675);
DISPLAY 0.638298 (-9565 5675);
PAINT PINK (-9565 5675);
DISPLAY INVISIBLE (-9565 5675);
FORCEPROP 1 LAST CDS_LMAN_SYM_OUTLINE -9475,6775,100,-125
J 0
(-1675 425);
DISPLAY 0.468085 (-1675 425);
PAINT GREEN (-1675 425);
DISPLAY INVISIBLE (-1675 425);
FORCEPROP 2 LAST CDS_LIB pure_quanta
J 0
(-1675 425);
DISPLAY INVISIBLE (-1675 425);
FORCEPROP 2 LAST CDS_XR_PAGE_TITLE CR-192 : @T6G_MB_LIB.T6G(SCH_1):PAGE192
J 0
(-9565 5675);
DISPLAY 0.638298 (-9565 5675);
PAINT PINK (-9565 5675);
DISPLAY INVISIBLE (-9565 5675);
FORCEPROP 1 LAST Q_DEPT BU9
J 1
(-5438 474);
DISPLAY 1.957447 (-5438 474);
PAINT GREEN (-5438 474);
DISPLAY INVISIBLE (-5438 474);
FORCEPROP 1 LAST COMMENT_BODY TRUE
J 0
(-1663 412);
DISPLAY 0.978723 (-1663 412);
PAINT GREEN (-1663 412);
DISPLAY INVISIBLE (-1663 412);
FORCEADD DNS..1
(-8500 3325);
PAINT RED (-8500 3325);
FORCEPROP 2 LAST CDS_LIB mstr_misc
J 0
(-8500 3325);
DISPLAY INVISIBLE (-8500 3325);
FORCEPROP 1 LAST COMMENT_BODY TRUE
J 0
(-8500 3325);
DISPLAY INVISIBLE (-8500 3325);
WIRE 16 -1 (-8450 2275)(-8450 2400);
WIRE 16 -1 (-7875 2350)(-7875 2475);
WIRE 16 -1 (-8050 3400)(-8225 3400);
WIRE 16 -1 (-8225 3400)(-8225 3275);
WIRE 16 -1 (-6125 2650)(-6125 2600);
WIRE 16 -1 (-6475 3000)(-5775 3000);
WIRE 16 -1 (-5775 3000)(-5775 2600);
WIRE 16 -1 (-5175 2175)(-5175 2300);
WIRE 16 -1 (-6375 4550)(-6375 4700);
WIRE 16 -1 (-4850 3850)(-4850 3800);
WIRE 16 -1 (-8475 3275)(-8475 3325);
WIRE 16 -1 (-10550 4350)(-10550 4175);
WIRE 17 273 (-10800 1300)(-8625 1300);
WIRE 17 273 (-10800 1800)(-10800 1300);
WIRE 17 273 (-8625 1800)(-8625 1300);
WIRE 17 273 (-10800 1800)(-8625 1800);
WIRE 17 273 (-10800 650)(-8625 650);
WIRE 17 273 (-10800 1250)(-10800 650);
WIRE 17 273 (-8625 1250)(-8625 650);
WIRE 17 273 (-10800 1250)(-8625 1250);
WIRE 17 273 (-3675 6925)(-1875 6925);
WIRE 17 273 (-3675 6925)(-3675 5825);
WIRE 17 273 (-1875 6925)(-1875 5825);
WIRE 17 273 (-3675 5825)(-1875 5825);
WIRE 16 -1 (-4850 4050)(-4850 4100);
WIRE 16 -1 (-4225 4100)(-4850 4100);
WIRE 16 -1 (-4850 4100)(-5125 4100);
FORCEPROP 2 LAST SIG_NAME FM_PWRGD_PVDD33_S5
J 0
(-4950 4100);
DISPLAY 0.489362 (-4950 4100);
WIRE 16 -1 (-6475 4100)(-6375 4100);
WIRE 16 -1 (-5325 4100)(-6375 4100);
FORCEPROP 2 LAST SIG_NAME PWRGD_PVDD33_S5
J 0
(-6025 4110);
DISPLAY 0.489362 (-6025 4110);
FORCEPROP 2 LASTPROP $XRERR UNIQUE?
J 0
(-6265 4110);
DISPLAY 0.638298 (-6265 4110);
PAINT MONO (-6265 4110);
DISPLAY INVISIBLE (-6265 4110);
WIRE 16 -1 (-6375 4100)(-6375 4350);
WIRE 16 -1 (-7850 4250)(-7850 4375);
WIRE 16 -1 (-8275 4250)(-7850 4250);
WIRE 16 -1 (-8275 4375)(-8275 4250);
WIRE 16 -1 (-8675 4250)(-8275 4250);
WIRE 16 -1 (-8675 4375)(-8675 4250);
WIRE 16 -1 (-8675 4250)(-9025 4250);
WIRE 16 -1 (-9025 4400)(-9025 4250);
WIRE 16 -1 (-9025 4250)(-9175 4250);
WIRE 16 -1 (-9275 4250)(-9175 4250);
WIRE 16 -1 (-9175 4250)(-9175 4150);
WIRE 16 -1 (-9275 4400)(-9275 4250);
WIRE 16 -1 (-9600 4250)(-9275 4250);
WIRE 16 -1 (-9600 4400)(-9600 4250);
WIRE 16 -1 (-6375 2800)(-6375 2750);
WIRE 16 -1 (-6475 2800)(-6375 2800);
WIRE 16 -1 (-6375 2600)(-6375 2750);
WIRE 16 -1 (-6375 2750)(-6475 2750);
WIRE 16 -1 (-4575 3200)(-4575 3000);
WIRE 16 -1 (-4575 3000)(-4275 3000);
WIRE 16 -1 (-4275 3000)(-3975 3000);
WIRE 16 -1 (-4275 3200)(-4275 3000);
WIRE 16 -1 (-3975 3200)(-3975 3000);
WIRE 16 -1 (-3975 3000)(-3675 3000);
WIRE 16 -1 (-3675 3200)(-3675 3000);
WIRE 16 -1 (-3675 3000)(-3275 3000);
WIRE 16 -1 (-3275 3200)(-3275 3000);
WIRE 16 -1 (-3275 3000)(-3275 2950);
WIRE 16 -1 (-4750 3600)(-4575 3600);
WIRE 16 -1 (-4575 3600)(-4275 3600);
WIRE 16 -1 (-4575 3400)(-4575 3600);
WIRE 16 -1 (-4275 3600)(-3975 3600);
WIRE 16 -1 (-4275 3400)(-4275 3600);
WIRE 16 -1 (-3975 3600)(-3675 3600);
WIRE 16 -1 (-3975 3400)(-3975 3600);
WIRE 16 -1 (-3275 3600)(-3675 3600);
WIRE 16 -1 (-3675 3400)(-3675 3600);
WIRE 16 -1 (-2825 3600)(-3275 3600);
WIRE 16 -1 (-3275 3400)(-3275 3600);
WIRE 16 -1 (-2825 3700)(-2825 3600);
WIRE 16 -1 (-2825 2650)(-2825 3600);
WIRE 16 -1 (-3775 2650)(-2825 2650);
WIRE 16 -1 (-3775 2650)(-3775 2250);
WIRE 16 -1 (-4125 2650)(-3775 2650);
WIRE 16 -1 (-4125 2250)(-3775 2250);
WIRE 16 -1 (-7275 3150)(-8150 3150);
WIRE 16 -1 (-8150 2825)(-8150 3150);
WIRE 16 -1 (-8450 2825)(-8150 2825);
WIRE 16 -1 (-8450 2600)(-8450 2825);
WIRE 16 -1 (-8450 3000)(-8450 2825);
WIRE 16 -1 (-10450 4650)(-10150 4650);
WIRE 16 -1 (-10450 4800)(-10450 4650);
WIRE 16 -1 (-10550 4650)(-10450 4650);
WIRE 16 -1 (-10550 4550)(-10550 4650);
WIRE 16 -1 (-5425 3625)(-5425 3600);
WIRE 16 -1 (-4950 3600)(-5425 3600);
WIRE 16 -1 (-6475 3600)(-5425 3600);
FORCEPROP 2 LAST SIG_NAME SW_PVDD_33_S5_SW
J 0
(-6410 3610);
DISPLAY 0.489362 (-6410 3610);
FORCEPROP 2 LASTPROP $XRERR UNIQUE?
J 0
(-6650 3610);
DISPLAY 0.638298 (-6650 3610);
PAINT MONO (-6650 3610);
DISPLAY INVISIBLE (-6650 3610);
WIRE 16 -1 (-5425 3900)(-5425 3825);
WIRE 16 -1 (-5650 3900)(-5425 3900);
FORCEPROP 2 LAST SIG_NAME SW_PVDD_33_S5_BST_R
J 0
(-5610 3910);
DISPLAY 0.446809 (-5610 3910);
FORCEPROP 2 LASTPROP $XRERR UNIQUE?
J 0
(-5850 3910);
DISPLAY 0.638298 (-5850 3910);
PAINT MONO (-5850 3910);
DISPLAY INVISIBLE (-5850 3910);
WIRE 16 -1 (-5850 3900)(-6475 3900);
FORCEPROP 2 LAST SIG_NAME SW_PVDD_33_S5_BST
J 0
(-6410 3910);
DISPLAY 0.489362 (-6410 3910);
FORCEPROP 2 LASTPROP $XRERR UNIQUE?
J 0
(-6650 3910);
DISPLAY 0.638298 (-6650 3910);
PAINT MONO (-6650 3910);
DISPLAY INVISIBLE (-6650 3910);
WIRE 16 -1 (-6125 2850)(-6125 2900);
WIRE 16 -1 (-6125 2900)(-6475 2900);
FORCEPROP 2 LAST SIG_NAME PVDD_33_S5_REF
J 0
(-6410 2910);
DISPLAY 0.489362 (-6410 2910);
FORCEPROP 2 LASTPROP $XRERR UNIQUE?
J 0
(-6650 2910);
DISPLAY 0.638298 (-6650 2910);
PAINT MONO (-6650 2910);
DISPLAY INVISIBLE (-6650 2910);
WIRE 16 -1 (-7275 3400)(-7850 3400);
FORCEPROP 2 LAST SIG_NAME PVDD_33_S5_MODE
J 0
(-7710 3410);
DISPLAY 0.489362 (-7710 3410);
FORCEPROP 2 LASTPROP $XRERR UNIQUE?
J 0
(-7950 3410);
DISPLAY 0.638298 (-7950 3410);
PAINT MONO (-7950 3410);
DISPLAY INVISIBLE (-7950 3410);
WIRE 16 -1 (-8725 3600)(-8475 3600);
WIRE 16 -1 (-8475 3600)(-7275 3600);
FORCEPROP 2 LAST SIG_NAME PVDD33_S5_EN
J 0
(-8375 3610);
DISPLAY 0.489362 (-8375 3610);
WIRE 16 -1 (-8475 3600)(-8475 3525);
WIRE 16 -1 (-4325 2250)(-4675 2250);
WIRE 16 -1 (-4675 2650)(-4675 2250);
WIRE 16 -1 (-4325 2650)(-4675 2650);
WIRE 16 -1 (-4675 2650)(-5175 2650);
WIRE 16 -1 (-5175 2650)(-5425 2650);
WIRE 16 -1 (-5175 2650)(-5175 2500);
WIRE 16 -1 (-5425 2650)(-5425 3150);
WIRE 16 -1 (-5425 3150)(-6475 3150);
FORCEPROP 2 LAST SIG_NAME PVDD_33_S5_FB
J 0
(-6410 3160);
DISPLAY 0.489362 (-6410 3160);
FORCEPROP 2 LASTPROP $XRERR UNIQUE?
J 0
(-6650 3160);
DISPLAY 0.638298 (-6650 3160);
PAINT MONO (-6650 3160);
DISPLAY INVISIBLE (-6650 3160);
WIRE 16 -1 (-7275 2800)(-7875 2800);
FORCEPROP 2 LAST SIG_NAME PVDD_33_S5_CS
J 0
(-7685 2810);
DISPLAY 0.489362 (-7685 2810);
FORCEPROP 2 LASTPROP $XRERR UNIQUE?
J 0
(-7925 2810);
DISPLAY 0.638298 (-7925 2810);
PAINT MONO (-7925 2810);
DISPLAY INVISIBLE (-7925 2810);
WIRE 16 -1 (-7875 2800)(-7875 2675);
WIRE 16 -1 (-7275 4050)(-7375 4050);
WIRE 16 -1 (-7375 4050)(-7375 4100);
WIRE 16 -1 (-7275 4100)(-7375 4100);
WIRE 16 -1 (-7375 4100)(-7375 4650);
WIRE 16 -1 (-7375 4650)(-7850 4650);
WIRE 16 -1 (-7850 4575)(-7850 4650);
WIRE 16 -1 (-8275 4650)(-7850 4650);
WIRE 16 -1 (-8675 4650)(-8275 4650);
FORCEPROP 2 LAST SIG_NAME SW_P12V_AUX_PVDD_33_S5_FLT
J 0
(-8660 4660);
DISPLAY 0.489362 (-8660 4660);
FORCEPROP 2 LASTPROP $XRERR UNIQUE?
J 0
(-8900 4660);
DISPLAY 0.638298 (-8900 4660);
PAINT MONO (-8900 4660);
DISPLAY INVISIBLE (-8900 4660);
WIRE 16 -1 (-8275 4650)(-8275 4575);
WIRE 16 -1 (-8675 4575)(-8675 4650);
WIRE 16 -1 (-8675 4650)(-9025 4650);
WIRE 16 -1 (-9025 4650)(-9025 4600);
WIRE 16 -1 (-9275 4650)(-9025 4650);
WIRE 16 -1 (-9600 4650)(-9275 4650);
WIRE 16 -1 (-9275 4650)(-9275 4600);
WIRE 16 -1 (-9600 4650)(-9600 4600);
WIRE 16 -1 (-9950 4650)(-9600 4650);
DOT 1 (-4575 3600);
DOT 1 (-5425 3600);
DOT 1 (-4275 3600);
DOT 1 (-4850 4100);
DOT 1 (-2825 3600);
DOT 1 (-3275 3600);
DOT 1 (-3675 3600);
DOT 1 (-3275 3000);
DOT 1 (-3675 3000);
DOT 1 (-3975 3600);
DOT 1 (-3975 3000);
DOT 1 (-3775 2650);
DOT 1 (-7375 4100);
DOT 1 (-7850 4650);
DOT 1 (-8275 4650);
DOT 1 (-4275 3000);
DOT 1 (-4675 2650);
DOT 1 (-5175 2650);
DOT 1 (-6375 2750);
DOT 1 (-8475 3600);
DOT 1 (-8450 2825);
DOT 1 (-10450 4650);
DOT 1 (-9600 4650);
DOT 1 (-9025 4650);
DOT 1 (-9275 4650);
DOT 1 (-8675 4650);
DOT 1 (-9025 4250);
DOT 1 (-6375 4100);
DOT 1 (-8275 4250);
DOT 1 (-9275 4250);
DOT 1 (-9175 4250);
DOT 1 (-8675 4250);
FORCENOTE
BOM CHANGE R&C TABLE
(-10725 1150) 0;
DISPLAY LEFT (-10725 1150);
DISPLAY 1.276596 (-10725 1150);
PAINT WHITE (-10725 1150);
FORCENOTE
1ST
(-10725 1000) 0;
DISPLAY LEFT (-10725 1000);
DISPLAY 1.021277 (-10725 1000);
PAINT WHITE (-10725 1000);
FORCENOTE
1ST AL008633007/MPQ8633AGLE-C807-Z/MPS
(-10725 1550) 0;
DISPLAY LEFT (-10725 1550);
DISPLAY 1.021277 (-10725 1550);
PAINT WHITE (-10725 1550);
FORCENOTE
WORK FREQUENCY=600KHZ
(-3575 6088) 0;
DISPLAY LEFT (-3575 6088);
DISPLAY 1.276596 (-3575 6088);
PAINT WHITE (-3575 6088);
FORCENOTE
SLEW RATE=2A/US
(-3575 6170) 0;
DISPLAY LEFT (-3575 6170);
DISPLAY 1.170213 (-3575 6170);
PAINT WHITE (-3575 6170);
FORCENOTE
EFFICENCY>90%@TDC
(-3575 6000) 0;
DISPLAY LEFT (-3575 6000);
DISPLAY 1.170213 (-3575 6000);
PAINT WHITE (-3575 6000);
FORCENOTE
EDC=6.2A
(-3575 6395) 0;
DISPLAY LEFT (-3575 6395);
DISPLAY 1.170213 (-3575 6395);
PAINT WHITE (-3575 6395);
FORCENOTE
OVER CURRENT PROTECTION=9A
(-3575 6320) 0;
DISPLAY LEFT (-3575 6320);
DISPLAY 1.170213 (-3575 6320);
PAINT WHITE (-3575 6320);
FORCENOTE
CURRENT STEP=2A
(-3575 6245) 0;
DISPLAY LEFT (-3575 6245);
DISPLAY 1.170213 (-3575 6245);
PAINT WHITE (-3575 6245);
FORCENOTE
DCR=15MOHM 
(-5350 3475) 0;
DISPLAY LEFT (-5350 3475);
DISPLAY 1.021277 (-5350 3475);
PAINT WHITE (-5350 3475);
FORCENOTE
ISAT=16A@100C
(-5350 3400) 0;
DISPLAY LEFT (-5350 3400);
DISPLAY 1.021277 (-5350 3400);
PAINT WHITE (-5350 3400);
FORCENOTE
PCMC063-1R5MN
(-5350 3325) 0;
DISPLAY LEFT (-5350 3325);
DISPLAY 1.021277 (-5350 3325);
PAINT WHITE (-5350 3325);
FORCENOTE
2ND=CV-15I0MZ03
(-5350 3175) 0;
DISPLAY LEFT (-5350 3175);
DISPLAY 1.021277 (-5350 3175);
PAINT WHITE (-5350 3175);
FORCENOTE
7*7*3
(-5350 3250) 0;
DISPLAY LEFT (-5350 3250);
DISPLAY 1.021277 (-5350 3250);
PAINT WHITE (-5350 3250);
FORCENOTE
DCR=5M OHM
(-10300 4525) 0;
DISPLAY LEFT (-10300 4525);
DISPLAY 0.808511 (-10300 4525);
PAINT WHITE (-10300 4525);
FORCENOTE
2ND=CX220Z06Z00
(-10300 4475) 0;
DISPLAY LEFT (-10300 4475);
DISPLAY 0.808511 (-10300 4475);
PAINT WHITE (-10300 4475);
FORCENOTE
3RD=CX000220000
(-10300 4425) 0;
DISPLAY LEFT (-10300 4425);
DISPLAY 0.808511 (-10300 4425);
PAINT WHITE (-10300 4425);
FORCENOTE
3RD AL000548006/TPS548A28RWWR/TI
(-10725 1350) 0;
DISPLAY LEFT (-10725 1350);
DISPLAY 1.021277 (-10725 1350);
PAINT WHITE (-10725 1350);
FORCENOTE
 BOM NOTE
(-10775 1700) 0;
DISPLAY LEFT (-10775 1700);
DISPLAY 1.276596 (-10775 1700);
PAINT WHITE (-10775 1700);
FORCENOTE
3RD PC118 CHANGE TO CH5222KEB01
(-10725 825) 0;
DISPLAY LEFT (-10725 825);
DISPLAY 1.021277 (-10725 825);
PAINT WHITE (-10725 825);
FORCENOTE
2ND AL053318002/RS53318LR/REEDSEMI
(-10725 1450) 0;
DISPLAY LEFT (-10725 1450);
DISPLAY 1.021277 (-10725 1450);
PAINT WHITE (-10725 1450);
FORCENOTE
2ND NA 
(-10725 925) 0;
DISPLAY LEFT (-10725 925);
DISPLAY 1.021277 (-10725 925);
PAINT WHITE (-10725 925);
FORCENOTE
VOUT=0.6(1+RA/RB)=3.3V
(-6050 1875) 0;
DISPLAY LEFT (-6050 1875);
DISPLAY 1.595745 (-6050 1875);
PAINT WHITE (-6050 1875);
FORCENOTE
TDC=6A
(-3575 6488) 0;
DISPLAY LEFT (-3575 6488);
DISPLAY 1.170213 (-3575 6488);
PAINT WHITE (-3575 6488);
FORCENOTE
DC & AC=3.13-3.46V
(-3575 6569) 0;
DISPLAY LEFT (-3575 6569);
DISPLAY 1.170213 (-3575 6569);
PAINT WHITE (-3575 6569);
FORCENOTE
OUTPUT VOLTAGE=3.3V
(-3575 6650) 0;
DISPLAY LEFT (-3575 6650);
DISPLAY 1.170213 (-3575 6650);
PAINT WHITE (-3575 6650);
FORCENOTE
PVDD_33_S5 SPECIFICATION
(-3575 6775) 0;
DISPLAY LEFT (-3575 6775);
DISPLAY 1.468085 (-3575 6775);
PAINT WHITE (-3575 6775);
FORCENOTE
PVDD_33_S5
(-7925 5525) 0;
DISPLAY LEFT (-7925 5525);
DISPLAY 4.914894 (-7925 5525);
PAINT WHITE (-7925 5525);
FORCENOTE
FCCM/FSW=600KHZ
(-9525 2950) 0;
DISPLAY LEFT (-9525 2950);
DISPLAY 1.276596 (-9525 2950);
PAINT WHITE (-9525 2950);
FORCENOTE
RA
(-4325 2800) 0;
DISPLAY LEFT (-4325 2800);
DISPLAY 1.021277 (-4325 2800);
PAINT WHITE (-4325 2800);
FORCENOTE
RB
(-5300 2400) 0;
DISPLAY LEFT (-5300 2400);
DISPLAY 1.021277 (-5300 2400);
PAINT WHITE (-5300 2400);
FORCENOTE
IRATED=5A@125C
(-10300 4575) 0;
DISPLAY LEFT (-10300 4575);
DISPLAY 0.808511 (-10300 4575);
PAINT WHITE (-10300 4575);
QUIT
